(kicad_sch
	(version 20250114)
	(generator "eeschema")
	(generator_version "9.0")
	(paper "A3")
	(title_block
		(title "OCuLink to 10GbE adapter")
		(date "2026-02-23")
		(rev "1.1.0")
		(company "Antmicro Ltd")
		(comment 1 "www.antmicro.com")
	)
	(text "Fan Controller"
		(exclude_from_sim no)
		(at 204.47 100.33 0)
		(effects
			(font
				(size 2.54 2.54)
				(thickness 0.508)
				(bold yes)
			)
		)
	)
	(text "100%"
		(exclude_from_sim no)
		(at 198.882 255.524 0)
		(effects
			(font
				(size 1.27 1.27)
			)
			(justify right)
		)
	)
	(text "0%"
		(exclude_from_sim no)
		(at 198.882 270.764 0)
		(effects
			(font
				(size 1.27 1.27)
			)
			(justify right)
		)
	)
	(text "Duty cycle [%]"
		(exclude_from_sim no)
		(at 199.39 252.73 0)
		(effects
			(font
				(size 1.27 1.27)
			)
		)
	)
	(text "T[°C]"
		(exclude_from_sim no)
		(at 225.298 270.764 0)
		(effects
			(font
				(size 1.27 1.27)
			)
			(justify left)
		)
	)
	(text "38°C"
		(exclude_from_sim no)
		(at 203.2 272.288 0)
		(effects
			(font
				(size 1.27 1.27)
			)
		)
	)
	(text "50°C"
		(exclude_from_sim no)
		(at 218.44 272.288 0)
		(effects
			(font
				(size 1.27 1.27)
			)
		)
	)
	(text "ICT Testpoints\nplace on bottom"
		(exclude_from_sim no)
		(at 76.2 189.738 0)
		(effects
			(font
				(size 1.27 1.27)
			)
		)
	)
	(text "18%"
		(exclude_from_sim no)
		(at 198.882 266.954 0)
		(effects
			(font
				(size 1.27 1.27)
			)
			(justify right)
		)
	)
	(text_box "Select this resistance equal\nto the resistance of the \nthermistor at the\ndesired value of TSTART.\n\nTSTART ≈ 38°C"
		(exclude_from_sim no)
		(at 123.19 123.19 0)
		(size 39.37 12.7)
		(margins 0.9525 0.9525 0.9525 0.9525)
		(stroke
			(width 0)
			(type solid)
		)
		(fill
			(type none)
		)
		(effects
			(font
				(size 1.27 1.27)
			)
			(justify left)
		)
	)
	(text_box "D_{MIN} = 2 * R_{L}/(R_{L}+R_{H}) [%]\n\nD_{MIN} = 2 * 1k/(1k+10k) = 18%"
		(exclude_from_sim no)
		(at 137.16 165.1 0)
		(size 45.72 17.78)
		(margins 0.9525 0.9525 0.9525 0.9525)
		(stroke
			(width 0)
			(type solid)
		)
		(fill
			(type none)
		)
		(effects
			(font
				(size 1.27 1.27)
			)
			(justify left)
		)
	)
	(text_box "Reference"
		(exclude_from_sim no)
		(at 161.29 213.36 0)
		(size 99.06 3.81)
		(margins 0.9525 0.9525 0.9525 0.9525)
		(stroke
			(width 0)
			(type solid)
		)
		(fill
			(type none)
		)
		(effects
			(font
				(size 1.27 1.27)
			)
			(justify left top)
		)
	)
	(text_box "f_{PWM} = 10.5455E^{-6}/C [Hz]\n\nf_{PWM} = 22kHz"
		(exclude_from_sim no)
		(at 233.68 140.97 0)
		(size 39.37 7.62)
		(margins 0.9525 0.9525 0.9525 0.9525)
		(stroke
			(width 0)
			(type solid)
		)
		(fill
			(type none)
		)
		(effects
			(font
				(size 1.27 1.27)
			)
			(justify right)
		)
	)
	(text_box "Designed temperature curve"
		(exclude_from_sim no)
		(at 191.77 246.38 0)
		(size 39.37 27.94)
		(margins 0.9525 0.9525 0.9525 0.9525)
		(stroke
			(width 0)
			(type solid)
		)
		(fill
			(type none)
		)
		(effects
			(font
				(size 1.27 1.27)
			)
			(justify left top)
		)
	)
	(junction
		(at 54.61 140.97)
		(diameter 0)
		(color 0 0 0 0)
	)
	(junction
		(at 279.4 127)
		(diameter 0)
		(color 0 0 0 0)
	)
	(junction
		(at 180.34 173.99)
		(diameter 0)
		(color 0 0 0 0)
	)
	(junction
		(at 180.34 163.83)
		(diameter 0)
		(color 0 0 0 0)
	)
	(junction
		(at 95.25 140.97)
		(diameter 0)
		(color 0 0 0 0)
	)
	(junction
		(at 59.69 140.97)
		(diameter 0)
		(color 0 0 0 0)
	)
	(junction
		(at 172.72 137.16)
		(diameter 0)
		(color 0 0 0 0)
	)
	(junction
		(at 218.44 147.32)
		(diameter 0)
		(color 0 0 0 0)
	)
	(junction
		(at 153.67 137.16)
		(diameter 0)
		(color 0 0 0 0)
	)
	(junction
		(at 193.04 173.99)
		(diameter 0)
		(color 0 0 0 0)
	)
	(no_connect
		(at 269.24 134.62)
	)
	(polyline
		(pts
			(xy 203.2 266.7) (xy 218.44 255.27)
		)
		(stroke
			(width 0)
			(type default)
		)
	)
	(wire
		(pts
			(xy 185.42 144.78) (xy 193.04 144.78)
		)
		(stroke
			(width 0)
			(type default)
		)
	)
	(wire
		(pts
			(xy 215.9 137.16) (xy 237.49 137.16)
		)
		(stroke
			(width 0)
			(type default)
		)
	)
	(polyline
		(pts
			(xy 203.2 266.7) (xy 203.2 270.51)
		)
		(stroke
			(width 0)
			(type default)
		)
	)
	(polyline
		(pts
			(xy 199.39 266.7) (xy 203.2 266.7)
		)
		(stroke
			(width 0)
			(type dot)
		)
	)
	(wire
		(pts
			(xy 271.78 124.46) (xy 271.78 127)
		)
		(stroke
			(width 0)
			(type default)
		)
	)
	(wire
		(pts
			(xy 313.69 132.08) (xy 317.5 132.08)
		)
		(stroke
			(width 0)
			(type default)
		)
	)
	(wire
		(pts
			(xy 172.72 139.7) (xy 172.72 137.16)
		)
		(stroke
			(width 0)
			(type default)
		)
	)
	(wire
		(pts
			(xy 267.97 116.84) (xy 271.78 116.84)
		)
		(stroke
			(width 0)
			(type default)
		)
	)
	(polyline
		(pts
			(xy 218.44 255.27) (xy 224.79 255.27)
		)
		(stroke
			(width 0)
			(type default)
		)
	)
	(wire
		(pts
			(xy 279.4 149.86) (xy 279.4 139.7)
		)
		(stroke
			(width 0)
			(type default)
		)
	)
	(wire
		(pts
			(xy 237.49 142.24) (xy 237.49 137.16)
		)
		(stroke
			(width 0)
			(type default)
		)
	)
	(polyline
		(pts
			(xy 199.39 255.27) (xy 218.44 255.27)
		)
		(stroke
			(width 0)
			(type dot)
		)
	)
	(wire
		(pts
			(xy 153.67 121.92) (xy 153.67 127)
		)
		(stroke
			(width 0)
			(type default)
		)
	)
	(wire
		(pts
			(xy 279.4 124.46) (xy 279.4 127)
		)
		(stroke
			(width 0)
			(type default)
		)
	)
	(wire
		(pts
			(xy 237.49 149.86) (xy 237.49 147.32)
		)
		(stroke
			(width 0)
			(type default)
		)
	)
	(wire
		(pts
			(xy 168.91 137.16) (xy 172.72 137.16)
		)
		(stroke
			(width 0)
			(type default)
		)
	)
	(wire
		(pts
			(xy 218.44 147.32) (xy 218.44 149.86)
		)
		(stroke
			(width 0)
			(type default)
		)
	)
	(wire
		(pts
			(xy 187.96 147.32) (xy 187.96 173.99)
		)
		(stroke
			(width 0)
			(type default)
		)
	)
	(polyline
		(pts
			(xy 199.39 270.51) (xy 224.79 270.51)
		)
		(stroke
			(width 0)
			(type default)
		)
	)
	(wire
		(pts
			(xy 193.04 173.99) (xy 193.04 176.53)
		)
		(stroke
			(width 0)
			(type default)
		)
	)
	(wire
		(pts
			(xy 78.74 146.05) (xy 76.2 146.05)
		)
		(stroke
			(width 0)
			(type default)
		)
	)
	(wire
		(pts
			(xy 54.61 138.43) (xy 54.61 140.97)
		)
		(stroke
			(width 0)
			(type default)
		)
	)
	(wire
		(pts
			(xy 215.9 132.08) (xy 281.94 132.08)
		)
		(stroke
			(width 0)
			(type default)
		)
	)
	(wire
		(pts
			(xy 78.74 151.13) (xy 78.74 146.05)
		)
		(stroke
			(width 0)
			(type default)
		)
	)
	(polyline
		(pts
			(xy 191.77 250.19) (xy 231.14 250.19)
		)
		(stroke
			(width 0)
			(type default)
		)
	)
	(wire
		(pts
			(xy 62.23 146.05) (xy 59.69 146.05)
		)
		(stroke
			(width 0)
			(type default)
		)
	)
	(wire
		(pts
			(xy 326.39 132.08) (xy 322.58 132.08)
		)
		(stroke
			(width 0)
			(type default)
		)
	)
	(wire
		(pts
			(xy 187.96 173.99) (xy 193.04 173.99)
		)
		(stroke
			(width 0)
			(type default)
		)
	)
	(wire
		(pts
			(xy 269.24 134.62) (xy 281.94 134.62)
		)
		(stroke
			(width 0)
			(type default)
		)
	)
	(wire
		(pts
			(xy 176.53 163.83) (xy 180.34 163.83)
		)
		(stroke
			(width 0)
			(type default)
		)
	)
	(wire
		(pts
			(xy 193.04 163.83) (xy 193.04 166.37)
		)
		(stroke
			(width 0)
			(type default)
		)
	)
	(wire
		(pts
			(xy 172.72 147.32) (xy 172.72 144.78)
		)
		(stroke
			(width 0)
			(type default)
		)
	)
	(wire
		(pts
			(xy 271.78 116.84) (xy 271.78 119.38)
		)
		(stroke
			(width 0)
			(type default)
		)
	)
	(wire
		(pts
			(xy 172.72 137.16) (xy 193.04 137.16)
		)
		(stroke
			(width 0)
			(type default)
		)
	)
	(wire
		(pts
			(xy 271.78 127) (xy 279.4 127)
		)
		(stroke
			(width 0)
			(type default)
		)
	)
	(wire
		(pts
			(xy 187.96 147.32) (xy 193.04 147.32)
		)
		(stroke
			(width 0)
			(type default)
		)
	)
	(wire
		(pts
			(xy 96.52 140.97) (xy 95.25 140.97)
		)
		(stroke
			(width 0)
			(type default)
		)
	)
	(polyline
		(pts
			(xy 199.39 270.51) (xy 203.2 270.51)
		)
		(stroke
			(width 0)
			(type default)
		)
	)
	(wire
		(pts
			(xy 153.67 137.16) (xy 153.67 139.7)
		)
		(stroke
			(width 0)
			(type default)
		)
	)
	(wire
		(pts
			(xy 95.25 140.97) (xy 76.2 140.97)
		)
		(stroke
			(width 0)
			(type default)
		)
	)
	(wire
		(pts
			(xy 279.4 139.7) (xy 281.94 139.7)
		)
		(stroke
			(width 0)
			(type default)
		)
	)
	(polyline
		(pts
			(xy 218.44 270.51) (xy 218.44 255.27)
		)
		(stroke
			(width 0)
			(type dot)
		)
	)
	(wire
		(pts
			(xy 54.61 149.86) (xy 54.61 151.13)
		)
		(stroke
			(width 0)
			(type default)
		)
	)
	(wire
		(pts
			(xy 279.4 116.84) (xy 279.4 119.38)
		)
		(stroke
			(width 0)
			(type default)
		)
	)
	(wire
		(pts
			(xy 83.82 144.78) (xy 83.82 143.51)
		)
		(stroke
			(width 0)
			(type default)
		)
	)
	(wire
		(pts
			(xy 95.25 151.13) (xy 95.25 149.86)
		)
		(stroke
			(width 0)
			(type default)
		)
	)
	(wire
		(pts
			(xy 59.69 140.97) (xy 59.69 146.05)
		)
		(stroke
			(width 0)
			(type default)
		)
	)
	(wire
		(pts
			(xy 218.44 144.78) (xy 218.44 147.32)
		)
		(stroke
			(width 0)
			(type default)
		)
	)
	(wire
		(pts
			(xy 215.9 144.78) (xy 218.44 144.78)
		)
		(stroke
			(width 0)
			(type default)
		)
	)
	(wire
		(pts
			(xy 180.34 181.61) (xy 180.34 184.15)
		)
		(stroke
			(width 0)
			(type default)
		)
	)
	(wire
		(pts
			(xy 71.12 195.58) (xy 78.74 195.58)
		)
		(stroke
			(width 0)
			(type default)
		)
	)
	(wire
		(pts
			(xy 185.42 144.78) (xy 185.42 173.99)
		)
		(stroke
			(width 0)
			(type default)
		)
	)
	(wire
		(pts
			(xy 185.42 173.99) (xy 180.34 173.99)
		)
		(stroke
			(width 0)
			(type default)
		)
	)
	(wire
		(pts
			(xy 224.79 142.24) (xy 224.79 139.7)
		)
		(stroke
			(width 0)
			(type default)
		)
	)
	(wire
		(pts
			(xy 193.04 171.45) (xy 193.04 173.99)
		)
		(stroke
			(width 0)
			(type default)
		)
	)
	(wire
		(pts
			(xy 322.58 132.08) (xy 322.58 133.35)
		)
		(stroke
			(width 0)
			(type default)
		)
	)
	(wire
		(pts
			(xy 224.79 149.86) (xy 224.79 147.32)
		)
		(stroke
			(width 0)
			(type default)
		)
	)
	(wire
		(pts
			(xy 54.61 144.78) (xy 54.61 140.97)
		)
		(stroke
			(width 0)
			(type default)
		)
	)
	(wire
		(pts
			(xy 218.44 147.32) (xy 215.9 147.32)
		)
		(stroke
			(width 0)
			(type default)
		)
	)
	(wire
		(pts
			(xy 149.86 121.92) (xy 153.67 121.92)
		)
		(stroke
			(width 0)
			(type default)
		)
	)
	(wire
		(pts
			(xy 83.82 143.51) (xy 76.2 143.51)
		)
		(stroke
			(width 0)
			(type default)
		)
	)
	(wire
		(pts
			(xy 185.42 132.08) (xy 193.04 132.08)
		)
		(stroke
			(width 0)
			(type default)
		)
	)
	(wire
		(pts
			(xy 279.4 127) (xy 279.4 137.16)
		)
		(stroke
			(width 0)
			(type default)
		)
	)
	(wire
		(pts
			(xy 317.5 132.08) (xy 317.5 133.35)
		)
		(stroke
			(width 0)
			(type default)
		)
	)
	(wire
		(pts
			(xy 83.82 149.86) (xy 83.82 151.13)
		)
		(stroke
			(width 0)
			(type default)
		)
	)
	(wire
		(pts
			(xy 180.34 173.99) (xy 180.34 176.53)
		)
		(stroke
			(width 0)
			(type default)
		)
	)
	(wire
		(pts
			(xy 95.25 140.97) (xy 95.25 144.78)
		)
		(stroke
			(width 0)
			(type default)
		)
	)
	(wire
		(pts
			(xy 153.67 144.78) (xy 153.67 147.32)
		)
		(stroke
			(width 0)
			(type default)
		)
	)
	(wire
		(pts
			(xy 54.61 140.97) (xy 59.69 140.97)
		)
		(stroke
			(width 0)
			(type default)
		)
	)
	(wire
		(pts
			(xy 322.58 138.43) (xy 322.58 140.97)
		)
		(stroke
			(width 0)
			(type default)
		)
	)
	(polyline
		(pts
			(xy 199.39 254) (xy 199.39 270.51)
		)
		(stroke
			(width 0)
			(type default)
		)
	)
	(wire
		(pts
			(xy 317.5 138.43) (xy 317.5 140.97)
		)
		(stroke
			(width 0)
			(type default)
		)
	)
	(wire
		(pts
			(xy 193.04 181.61) (xy 193.04 184.15)
		)
		(stroke
			(width 0)
			(type default)
		)
	)
	(wire
		(pts
			(xy 153.67 137.16) (xy 163.83 137.16)
		)
		(stroke
			(width 0)
			(type default)
		)
	)
	(wire
		(pts
			(xy 180.34 163.83) (xy 180.34 166.37)
		)
		(stroke
			(width 0)
			(type default)
		)
	)
	(wire
		(pts
			(xy 153.67 132.08) (xy 153.67 137.16)
		)
		(stroke
			(width 0)
			(type default)
		)
	)
	(wire
		(pts
			(xy 281.94 137.16) (xy 279.4 137.16)
		)
		(stroke
			(width 0)
			(type default)
		)
	)
	(wire
		(pts
			(xy 180.34 163.83) (xy 193.04 163.83)
		)
		(stroke
			(width 0)
			(type default)
		)
	)
	(wire
		(pts
			(xy 215.9 139.7) (xy 224.79 139.7)
		)
		(stroke
			(width 0)
			(type default)
		)
	)
	(wire
		(pts
			(xy 59.69 140.97) (xy 62.23 140.97)
		)
		(stroke
			(width 0)
			(type default)
		)
	)
	(wire
		(pts
			(xy 180.34 171.45) (xy 180.34 173.99)
		)
		(stroke
			(width 0)
			(type default)
		)
	)
	(label "+5V"
		(at 71.12 195.58 0)
		(effects
			(font
				(size 1.27 1.27)
			)
			(justify left bottom)
		)
	)
	(label "TACH"
		(at 269.24 134.62 0)
		(effects
			(font
				(size 1.27 1.27)
			)
			(justify left bottom)
		)
	)
	(label "D0"
		(at 190.5 147.32 180)
		(effects
			(font
				(size 1.27 1.27)
			)
			(justify right bottom)
		)
	)
	(label "SENSE"
		(at 190.5 137.16 180)
		(effects
			(font
				(size 1.27 1.27)
			)
			(justify right bottom)
		)
	)
	(label "+5V"
		(at 185.42 132.08 0)
		(effects
			(font
				(size 1.27 1.27)
			)
			(justify left bottom)
		)
	)
	(label "+5V"
		(at 267.97 116.84 0)
		(effects
			(font
				(size 1.27 1.27)
			)
			(justify left bottom)
		)
	)
	(label "V_{FAN}"
		(at 273.05 127 0)
		(effects
			(font
				(size 1.27 1.27)
			)
			(justify left bottom)
		)
	)
	(label "+5V"
		(at 95.25 140.97 180)
		(effects
			(font
				(size 1.27 1.27)
			)
			(justify right bottom)
		)
	)
	(label "PWM"
		(at 269.24 132.08 0)
		(effects
			(font
				(size 1.27 1.27)
			)
			(justify left bottom)
		)
	)
	(label "+5V"
		(at 176.53 163.83 0)
		(effects
			(font
				(size 1.27 1.27)
			)
			(justify left bottom)
		)
	)
	(label "DMIN"
		(at 190.5 144.78 180)
		(effects
			(font
				(size 1.27 1.27)
			)
			(justify right bottom)
		)
	)
	(label "+5V"
		(at 149.86 121.92 0)
		(effects
			(font
				(size 1.27 1.27)
			)
			(justify left bottom)
		)
	)
	(label "V_{FAN}"
		(at 326.39 132.08 180)
		(effects
			(font
				(size 1.27 1.27)
			)
			(justify right bottom)
		)
	)
	(label "FREQ"
		(at 218.44 137.16 0)
		(effects
			(font
				(size 1.27 1.27)
			)
			(justify left bottom)
		)
	)
	(label "PWM"
		(at 313.69 132.08 0)
		(effects
			(font
				(size 1.27 1.27)
			)
			(justify left bottom)
		)
	)
	(label "SLOPE"
		(at 218.44 139.7 0)
		(effects
			(font
				(size 1.27 1.27)
			)
			(justify left bottom)
		)
	)
	(symbol
		(lib_id "antmicropower:GND")
		(at 224.79 149.86 0)
		(unit 1)
		(exclude_from_sim no)
		(in_bom yes)
		(on_board yes)
		(dnp no)
		(property "Reference" "#PWR0348"
			(at 233.68 152.4 0)
			(effects
				(font
					(size 1.27 1.27)
					(thickness 0.15)
				)
				(justify left bottom)
				(hide yes)
			)
		)
		(property "Value" "GND"
			(at 224.79 153.67 0)
			(effects
				(font
					(size 1.27 1.27)
					(thickness 0.15)
				)
			)
		)
		(property "Footprint" ""
			(at 233.68 157.48 0)
			(effects
				(font
					(size 1.27 1.27)
					(thickness 0.15)
				)
				(justify left bottom)
				(hide yes)
			)
		)
		(property "Datasheet" ""
			(at 233.68 162.56 0)
			(effects
				(font
					(size 1.27 1.27)
					(thickness 0.15)
				)
				(justify left bottom)
				(hide yes)
			)
		)
		(property "Description" ""
			(at 224.79 149.86 0)
			(effects
				(font
					(size 1.27 1.27)
				)
				(hide yes)
			)
		)
		(property "Author" "Antmicro"
			(at 233.68 157.48 0)
			(effects
				(font
					(size 1.27 1.27)
					(thickness 0.15)
				)
				(justify left bottom)
				(hide yes)
			)
		)
		(property "License" "Apache-2.0"
			(at 233.68 160.02 0)
			(effects
				(font
					(size 1.27 1.27)
					(thickness 0.15)
				)
				(justify left bottom)
				(hide yes)
			)
		)
		(pin "1"
		)
		(instances
			(project "oculink-to-10gbe-adapter"
				(path ""
					(reference "#PWR0348")
					(unit 1)
				)
			)
		)
	)
	(symbol
		(lib_id "antmicroTestPoints:TP_1mm_SMD")
		(at 78.74 195.58 0)
		(unit 1)
		(exclude_from_sim no)
		(in_bom no)
		(on_board yes)
		(dnp no)
		(fields_autoplaced yes)
		(property "Reference" "TP36"
			(at 83.82 195.58 0)
			(effects
				(font
					(size 1.27 1.27)
					(thickness 0.15)
				)
				(justify left)
			)
		)
		(property "Value" "TP_1mm_SMD"
			(at 93.98 203.2 0)
			(effects
				(font
					(size 1.27 1.27)
					(thickness 0.15)
				)
				(justify left bottom)
				(hide yes)
			)
		)
		(property "Footprint" "antmicro-footprints:TP_SMD_1mm"
			(at 93.98 205.74 0)
			(effects
				(font
					(size 1.27 1.27)
					(thickness 0.15)
				)
				(justify left bottom)
				(hide yes)
			)
		)
		(property "Datasheet" ""
			(at 96.52 208.28 0)
			(effects
				(font
					(size 1.27 1.27)
					(thickness 0.15)
				)
				(justify left bottom)
				(hide yes)
			)
		)
		(property "Description" "Test point 1mm SMD"
			(at 93.98 215.9 0)
			(effects
				(font
					(size 1.27 1.27)
				)
				(justify left bottom)
				(hide yes)
			)
		)
		(property "MPN" ""
			(at 78.74 195.58 0)
			(effects
				(font
					(size 1.27 1.27)
				)
				(hide yes)
			)
		)
		(property "Manufacturer" ""
			(at 78.74 195.58 0)
			(effects
				(font
					(size 1.27 1.27)
				)
				(hide yes)
			)
		)
		(property "Author" "Antmicro"
			(at 93.98 210.82 0)
			(effects
				(font
					(size 1.27 1.27)
					(thickness 0.15)
				)
				(justify left bottom)
				(hide yes)
			)
		)
		(property "License" "Apache-2.0"
			(at 93.98 213.36 0)
			(effects
				(font
					(size 1.27 1.27)
					(thickness 0.15)
				)
				(justify left bottom)
				(hide yes)
			)
		)
		(pin "1"
		)
		(instances
			(project "oculink-to-10gbe-adapter"
				(path ""
					(reference "TP36")
					(unit 1)
				)
			)
		)
	)
	(symbol
		(lib_id "antmicroCapacitors0402:C_1u_25V_0402")
		(at 54.61 149.86 270)
		(mirror x)
		(unit 1)
		(exclude_from_sim no)
		(in_bom yes)
		(on_board yes)
		(dnp no)
		(property "Reference" "C212"
			(at 52.578 146.05 90)
			(effects
				(font
					(size 1.27 1.27)
					(thickness 0.15)
				)
				(justify right)
			)
		)
		(property "Value" "C_1u_25V_0402"
			(at 44.45 129.54 0)
			(effects
				(font
					(size 1.27 1.27)
					(thickness 0.15)
				)
				(justify left bottom)
				(hide yes)
			)
		)
		(property "Footprint" "antmicro-footprints:C_0402_1005Metric"
			(at 41.91 129.54 0)
			(effects
				(font
					(size 1.27 1.27)
					(thickness 0.15)
				)
				(justify left bottom)
				(hide yes)
			)
		)
		(property "Datasheet" "https://www.murata.com/products/productdetail?partno=GRM155R61E105KE11%23"
			(at 39.37 129.54 0)
			(effects
				(font
					(size 1.27 1.27)
					(thickness 0.15)
				)
				(justify left bottom)
				(hide yes)
			)
		)
		(property "Description" "SMD Multilayer Ceramic Capacitor, 1 µF, 25 V, 0402 [1005 Metric], ± 10%, X5R, GRM Series"
			(at 21.59 129.54 0)
			(effects
				(font
					(size 1.27 1.27)
				)
				(justify left bottom)
				(hide yes)
			)
		)
		(property "MPN" "GRM155R61E105KE11J"
			(at 36.83 129.54 0)
			(effects
				(font
					(size 1.27 1.27)
					(thickness 0.15)
				)
				(justify left bottom)
				(hide yes)
			)
		)
		(property "Manufacturer" "Murata"
			(at 34.29 129.54 0)
			(effects
				(font
					(size 1.27 1.27)
					(thickness 0.15)
				)
				(justify left bottom)
				(hide yes)
			)
		)
		(property "License" "Apache-2.0"
			(at 31.75 129.54 0)
			(effects
				(font
					(size 1.27 1.27)
					(thickness 0.15)
				)
				(justify left bottom)
				(hide yes)
			)
		)
		(property "Author" "Antmicro"
			(at 29.21 129.54 0)
			(effects
				(font
					(size 1.27 1.27)
					(thickness 0.15)
				)
				(justify left bottom)
				(hide yes)
			)
		)
		(property "Val" "1u"
			(at 52.578 148.59 90)
			(effects
				(font
					(size 1.27 1.27)
					(thickness 0.15)
				)
				(justify right)
			)
		)
		(property "Voltage" "25V"
			(at 26.67 129.54 0)
			(effects
				(font
					(size 1.27 1.27)
				)
				(justify left bottom)
				(hide yes)
			)
		)
		(property "Dielectric" "X5R"
			(at 24.13 129.54 0)
			(effects
				(font
					(size 1.27 1.27)
				)
				(justify left bottom)
				(hide yes)
			)
		)
		(pin "1"
		)
		(pin "2"
		)
		(instances
			(project "oculink-to-10gbe-adapter"
				(path ""
					(reference "C212")
					(unit 1)
				)
			)
		)
	)
	(symbol
		(lib_id "antmicroTVSDiodes:SZSMF4L14AT3G")
		(at 322.58 133.35 90)
		(mirror x)
		(unit 1)
		(exclude_from_sim no)
		(in_bom yes)
		(on_board yes)
		(dnp no)
		(fields_autoplaced yes)
		(property "Reference" "D14"
			(at 325.12 134.62 90)
			(effects
				(font
					(size 1.27 1.27)
					(thickness 0.15)
				)
				(justify right)
			)
		)
		(property "Value" "SZSMF4L14AT3G"
			(at 332.74 148.59 0)
			(effects
				(font
					(size 1.27 1.27)
					(thickness 0.15)
				)
				(justify left bottom)
				(hide yes)
			)
		)
		(property "Footprint" "antmicro-footprints:SOD-123FL"
			(at 335.28 148.59 0)
			(effects
				(font
					(size 1.27 1.27)
					(thickness 0.15)
				)
				(justify left bottom)
				(hide yes)
			)
		)
		(property "Datasheet" "https://www.mouser.com/datasheet/2/240/media-3320461.pdf"
			(at 337.82 148.59 0)
			(effects
				(font
					(size 1.27 1.27)
					(thickness 0.15)
				)
				(justify left bottom)
				(hide yes)
			)
		)
		(property "Description" "ESD, TVS Diode, 14V, UNI, 400W, SOD-123FL"
			(at 322.58 133.35 0)
			(effects
				(font
					(size 1.27 1.27)
				)
				(hide yes)
			)
		)
		(property "MPN" "SZSMF4L12AT3G"
			(at 325.12 137.16 90)
			(effects
				(font
					(size 1.27 1.27)
					(thickness 0.15)
				)
				(justify right)
			)
		)
		(property "Author" "Antmicro"
			(at 340.36 148.59 0)
			(effects
				(font
					(size 1.27 1.27)
					(thickness 0.15)
				)
				(justify left bottom)
				(hide yes)
			)
		)
		(property "License" "Apache-2.0"
			(at 342.9 148.59 0)
			(effects
				(font
					(size 1.27 1.27)
					(thickness 0.15)
				)
				(justify left bottom)
				(hide yes)
			)
		)
		(property "Manufacturer" "Littelfuse"
			(at 345.44 148.59 0)
			(effects
				(font
					(size 1.27 1.27)
					(thickness 0.15)
				)
				(justify left bottom)
				(hide yes)
			)
		)
		(pin "1"
		)
		(pin "2"
		)
		(instances
			(project "oculink-to-10gbe-adapter"
				(path ""
					(reference "D14")
					(unit 1)
				)
			)
		)
	)
	(symbol
		(lib_id "antmicroResistors0402:R_10k_0402")
		(at 224.79 147.32 90)
		(unit 1)
		(exclude_from_sim no)
		(in_bom yes)
		(on_board yes)
		(dnp no)
		(property "Reference" "R180"
			(at 226.06 143.51 90)
			(effects
				(font
					(size 1.27 1.27)
					(thickness 0.15)
				)
				(justify right)
			)
		)
		(property "Value" "R_10k_0402"
			(at 237.49 127 0)
			(effects
				(font
					(size 1.27 1.27)
					(thickness 0.15)
				)
				(justify left bottom)
				(hide yes)
			)
		)
		(property "Footprint" "antmicro-footprints:R_0402_1005Metric"
			(at 240.03 127 0)
			(effects
				(font
					(size 1.27 1.27)
					(thickness 0.15)
				)
				(justify left bottom)
				(hide yes)
			)
		)
		(property "Datasheet" "https://www.bourns.com/docs/product-datasheets/cr.pdf"
			(at 242.57 127 0)
			(effects
				(font
					(size 1.27 1.27)
					(thickness 0.15)
				)
				(justify left bottom)
				(hide yes)
			)
		)
		(property "Description" "SMD Chip Resistor, 10 kohm, ± 1%, 62.5 mW, 0402 [1005 Metric], Thick Film, General Purpose"
			(at 255.27 127 0)
			(effects
				(font
					(size 1.27 1.27)
				)
				(justify left bottom)
				(hide yes)
			)
		)
		(property "MPN" "CR0402-FX-1002GLF"
			(at 245.11 127 0)
			(effects
				(font
					(size 1.27 1.27)
					(thickness 0.15)
				)
				(justify left bottom)
				(hide yes)
			)
		)
		(property "Manufacturer" "Bourns"
			(at 247.65 127 0)
			(effects
				(font
					(size 1.27 1.27)
					(thickness 0.15)
				)
				(justify left bottom)
				(hide yes)
			)
		)
		(property "License" "Apache-2.0"
			(at 250.19 127 0)
			(effects
				(font
					(size 1.27 1.27)
					(thickness 0.15)
				)
				(justify left bottom)
				(hide yes)
			)
		)
		(property "Author" "Antmicro"
			(at 252.73 127 0)
			(effects
				(font
					(size 1.27 1.27)
					(thickness 0.15)
				)
				(justify left bottom)
				(hide yes)
			)
		)
		(property "Val" "10k"
			(at 226.06 146.05 90)
			(effects
				(font
					(size 1.27 1.27)
					(thickness 0.15)
				)
				(justify right)
			)
		)
		(property "Tolerance" "1%"
			(at 234.95 127 0)
			(effects
				(font
					(size 1.27 1.27)
				)
				(justify left bottom)
				(hide yes)
			)
		)
		(pin "2"
		)
		(pin "1"
		)
		(instances
			(project "oculink-to-10gbe-adapter"
				(path ""
					(reference "R180")
					(unit 1)
				)
			)
		)
	)
	(symbol
		(lib_id "antmicroCapacitors0402:C_470p_0402")
		(at 237.49 147.32 90)
		(unit 1)
		(exclude_from_sim no)
		(in_bom yes)
		(on_board yes)
		(dnp no)
		(fields_autoplaced yes)
		(property "Reference" "C213"
			(at 240.03 143.5036 90)
			(effects
				(font
					(size 1.27 1.27)
					(thickness 0.15)
				)
				(justify right)
			)
		)
		(property "Value" "C_470p_0402"
			(at 247.65 127 0)
			(effects
				(font
					(size 1.27 1.27)
					(thickness 0.15)
				)
				(justify left bottom)
				(hide yes)
			)
		)
		(property "Footprint" "antmicro-footprints:C_0402_1005Metric"
			(at 250.19 127 0)
			(effects
				(font
					(size 1.27 1.27)
					(thickness 0.15)
				)
				(justify left bottom)
				(hide yes)
			)
		)
		(property "Datasheet" "https://www.passivecomponent.com/wp-content/uploads/datasheet/WTC_MLCC_General_Purpose.pdf"
			(at 252.73 127 0)
			(effects
				(font
					(size 1.27 1.27)
					(thickness 0.15)
				)
				(justify left bottom)
				(hide yes)
			)
		)
		(property "Description" "SMD Multilayer Ceramic Capacitor, General Purpose, 470 pF, 25 V, 0402 [1005 Metric], ± 10%, X7R"
			(at 270.51 127 0)
			(effects
				(font
					(size 1.27 1.27)
				)
				(justify left bottom)
				(hide yes)
			)
		)
		(property "MPN" "0402B471K250CT"
			(at 255.27 127 0)
			(effects
				(font
					(size 1.27 1.27)
					(thickness 0.15)
				)
				(justify left bottom)
				(hide yes)
			)
		)
		(property "Manufacturer" "Walsin"
			(at 257.81 127 0)
			(effects
				(font
					(size 1.27 1.27)
					(thickness 0.15)
				)
				(justify left bottom)
				(hide yes)
			)
		)
		(property "License" "Apache-2.0"
			(at 260.35 127 0)
			(effects
				(font
					(size 1.27 1.27)
					(thickness 0.15)
				)
				(justify left bottom)
				(hide yes)
			)
		)
		(property "Author" "Antmicro"
			(at 262.89 127 0)
			(effects
				(font
					(size 1.27 1.27)
					(thickness 0.15)
				)
				(justify left bottom)
				(hide yes)
			)
		)
		(property "Val" "470p"
			(at 240.03 146.0436 90)
			(effects
				(font
					(size 1.27 1.27)
					(thickness 0.15)
				)
				(justify right)
			)
		)
		(property "Voltage" "25V"
			(at 265.43 127 0)
			(effects
				(font
					(size 1.27 1.27)
				)
				(justify left bottom)
				(hide yes)
			)
		)
		(property "Dielectric" "X7R"
			(at 267.97 127 0)
			(effects
				(font
					(size 1.27 1.27)
				)
				(justify left bottom)
				(hide yes)
			)
		)
		(pin "2"
		)
		(pin "1"
		)
		(instances
			(project ""
				(path ""
					(reference "C213")
					(unit 1)
				)
			)
		)
	)
	(symbol
		(lib_id "antmicroResistors0402:R_0R_0402")
		(at 279.4 124.46 90)
		(unit 1)
		(exclude_from_sim no)
		(in_bom yes)
		(on_board yes)
		(dnp no)
		(property "Reference" "R181"
			(at 280.67 120.65 90)
			(effects
				(font
					(size 1.27 1.27)
					(thickness 0.15)
				)
				(justify right)
			)
		)
		(property "Value" "R_0R_0402"
			(at 292.1 104.14 0)
			(effects
				(font
					(size 1.27 1.27)
					(thickness 0.15)
				)
				(justify left bottom)
				(hide yes)
			)
		)
		(property "Footprint" "antmicro-footprints:R_0402_1005Metric"
			(at 294.64 104.14 0)
			(effects
				(font
					(size 1.27 1.27)
					(thickness 0.15)
				)
				(justify left bottom)
				(hide yes)
			)
		)
		(property "Datasheet" "https://industrial.panasonic.com/cdbs/www-data/pdf/RDA0000/AOA0000C301.pdf"
			(at 297.18 104.14 0)
			(effects
				(font
					(size 1.27 1.27)
					(thickness 0.15)
				)
				(justify left bottom)
				(hide yes)
			)
		)
		(property "Description" "SMD Chip Resistor, Jumper, 0 ohm, 100 mW, 0402 [1005 Metric], Thick Film, General Purpose"
			(at 312.42 104.14 0)
			(effects
				(font
					(size 1.27 1.27)
				)
				(justify left bottom)
				(hide yes)
			)
		)
		(property "MPN" "ERJ2GE0R00X"
			(at 299.72 104.14 0)
			(effects
				(font
					(size 1.27 1.27)
					(thickness 0.15)
				)
				(justify left bottom)
				(hide yes)
			)
		)
		(property "Manufacturer" "Panasonic"
			(at 302.26 104.14 0)
			(effects
				(font
					(size 1.27 1.27)
					(thickness 0.15)
				)
				(justify left bottom)
				(hide yes)
			)
		)
		(property "License" "Apache-2.0"
			(at 304.8 104.14 0)
			(effects
				(font
					(size 1.27 1.27)
					(thickness 0.15)
				)
				(justify left bottom)
				(hide yes)
			)
		)
		(property "Author" "Antmicro"
			(at 307.34 104.14 0)
			(effects
				(font
					(size 1.27 1.27)
					(thickness 0.15)
				)
				(justify left bottom)
				(hide yes)
			)
		)
		(property "Val" "0R"
			(at 280.67 123.19 90)
			(effects
				(font
					(size 1.27 1.27)
					(thickness 0.15)
				)
				(justify right)
			)
		)
		(property "Tolerance" "~"
			(at 289.56 104.14 0)
			(effects
				(font
					(size 1.27 1.27)
				)
				(justify left bottom)
				(hide yes)
			)
		)
		(property "Current" "1A"
			(at 309.88 104.14 0)
			(effects
				(font
					(size 1.27 1.27)
					(thickness 0.15)
				)
				(justify left bottom)
				(hide yes)
			)
		)
		(pin "2"
		)
		(pin "1"
		)
		(instances
			(project ""
				(path ""
					(reference "R181")
					(unit 1)
				)
			)
		)
	)
	(symbol
		(lib_id "antmicropower:GND")
		(at 193.04 184.15 0)
		(unit 1)
		(exclude_from_sim no)
		(in_bom yes)
		(on_board yes)
		(dnp no)
		(property "Reference" "#PWR0344"
			(at 201.93 186.69 0)
			(effects
				(font
					(size 1.27 1.27)
					(thickness 0.15)
				)
				(justify left bottom)
				(hide yes)
			)
		)
		(property "Value" "GND"
			(at 193.04 187.96 0)
			(effects
				(font
					(size 1.27 1.27)
					(thickness 0.15)
				)
			)
		)
		(property "Footprint" ""
			(at 201.93 191.77 0)
			(effects
				(font
					(size 1.27 1.27)
					(thickness 0.15)
				)
				(justify left bottom)
				(hide yes)
			)
		)
		(property "Datasheet" ""
			(at 201.93 196.85 0)
			(effects
				(font
					(size 1.27 1.27)
					(thickness 0.15)
				)
				(justify left bottom)
				(hide yes)
			)
		)
		(property "Description" ""
			(at 193.04 184.15 0)
			(effects
				(font
					(size 1.27 1.27)
				)
				(hide yes)
			)
		)
		(property "Author" "Antmicro"
			(at 201.93 191.77 0)
			(effects
				(font
					(size 1.27 1.27)
					(thickness 0.15)
				)
				(justify left bottom)
				(hide yes)
			)
		)
		(property "License" "Apache-2.0"
			(at 201.93 194.31 0)
			(effects
				(font
					(size 1.27 1.27)
					(thickness 0.15)
				)
				(justify left bottom)
				(hide yes)
			)
		)
		(pin "1"
		)
		(instances
			(project "oculink-to-10gbe-adapter"
				(path ""
					(reference "#PWR0344")
					(unit 1)
				)
			)
		)
	)
	(symbol
		(lib_id "antmicroResistors0402:R_0R_0402")
		(at 271.78 124.46 270)
		(mirror x)
		(unit 1)
		(exclude_from_sim no)
		(in_bom no)
		(on_board yes)
		(dnp yes)
		(property "Reference" "R174"
			(at 270.51 120.65 90)
			(effects
				(font
					(size 1.27 1.27)
					(thickness 0.15)
				)
				(justify right)
			)
		)
		(property "Value" "R_0R_0402"
			(at 259.08 104.14 0)
			(effects
				(font
					(size 1.27 1.27)
					(thickness 0.15)
				)
				(justify left bottom)
				(hide yes)
			)
		)
		(property "Footprint" "antmicro-footprints:R_0402_1005Metric"
			(at 256.54 104.14 0)
			(effects
				(font
					(size 1.27 1.27)
					(thickness 0.15)
				)
				(justify left bottom)
				(hide yes)
			)
		)
		(property "Datasheet" "https://industrial.panasonic.com/cdbs/www-data/pdf/RDA0000/AOA0000C301.pdf"
			(at 254 104.14 0)
			(effects
				(font
					(size 1.27 1.27)
					(thickness 0.15)
				)
				(justify left bottom)
				(hide yes)
			)
		)
		(property "Description" "SMD Chip Resistor, Jumper, 0 ohm, 100 mW, 0402 [1005 Metric], Thick Film, General Purpose"
			(at 238.76 104.14 0)
			(effects
				(font
					(size 1.27 1.27)
				)
				(justify left bottom)
				(hide yes)
			)
		)
		(property "MPN" "ERJ2GE0R00X"
			(at 251.46 104.14 0)
			(effects
				(font
					(size 1.27 1.27)
					(thickness 0.15)
				)
				(justify left bottom)
				(hide yes)
			)
		)
		(property "Manufacturer" "Panasonic"
			(at 248.92 104.14 0)
			(effects
				(font
					(size 1.27 1.27)
					(thickness 0.15)
				)
				(justify left bottom)
				(hide yes)
			)
		)
		(property "License" "Apache-2.0"
			(at 246.38 104.14 0)
			(effects
				(font
					(size 1.27 1.27)
					(thickness 0.15)
				)
				(justify left bottom)
				(hide yes)
			)
		)
		(property "Author" "Antmicro"
			(at 243.84 104.14 0)
			(effects
				(font
					(size 1.27 1.27)
					(thickness 0.15)
				)
				(justify left bottom)
				(hide yes)
			)
		)
		(property "Val" "0R"
			(at 270.51 123.19 90)
			(effects
				(font
					(size 1.27 1.27)
					(thickness 0.15)
				)
				(justify right)
			)
		)
		(property "Tolerance" "~"
			(at 261.62 104.14 0)
			(effects
				(font
					(size 1.27 1.27)
				)
				(justify left bottom)
				(hide yes)
			)
		)
		(property "Current" "1A"
			(at 241.3 104.14 0)
			(effects
				(font
					(size 1.27 1.27)
					(thickness 0.15)
				)
				(justify left bottom)
				(hide yes)
			)
		)
		(pin "2"
		)
		(pin "1"
		)
		(instances
			(project "oculink-to-10gbe-adapter"
				(path ""
					(reference "R174")
					(unit 1)
				)
			)
		)
	)
	(symbol
		(lib_id "antmicropower:VCC")
		(at 54.61 138.43 0)
		(unit 1)
		(exclude_from_sim no)
		(in_bom yes)
		(on_board yes)
		(dnp no)
		(property "Reference" "#PWR0362"
			(at 54.61 142.24 0)
			(effects
				(font
					(size 1.27 1.27)
				)
				(hide yes)
			)
		)
		(property "Value" "VCC"
			(at 54.61 134.62 0)
			(effects
				(font
					(size 1.27 1.27)
				)
			)
		)
		(property "Footprint" ""
			(at 54.61 138.43 0)
			(effects
				(font
					(size 1.27 1.27)
				)
				(hide yes)
			)
		)
		(property "Datasheet" ""
			(at 54.61 138.43 0)
			(effects
				(font
					(size 1.27 1.27)
				)
				(hide yes)
			)
		)
		(property "Description" ""
			(at 54.61 144.78 0)
			(effects
				(font
					(size 1.27 1.27)
				)
				(justify left bottom)
				(hide yes)
			)
		)
		(pin "1"
		)
		(instances
			(project "oculink-to-10gbe-adapter"
				(path ""
					(reference "#PWR0362")
					(unit 1)
				)
			)
		)
	)
	(symbol
		(lib_id "antmicropower:GND")
		(at 172.72 147.32 0)
		(unit 1)
		(exclude_from_sim no)
		(in_bom yes)
		(on_board yes)
		(dnp no)
		(property "Reference" "#PWR0342"
			(at 181.61 149.86 0)
			(effects
				(font
					(size 1.27 1.27)
					(thickness 0.15)
				)
				(justify left bottom)
				(hide yes)
			)
		)
		(property "Value" "GND"
			(at 172.72 151.13 0)
			(effects
				(font
					(size 1.27 1.27)
					(thickness 0.15)
				)
			)
		)
		(property "Footprint" ""
			(at 181.61 154.94 0)
			(effects
				(font
					(size 1.27 1.27)
					(thickness 0.15)
				)
				(justify left bottom)
				(hide yes)
			)
		)
		(property "Datasheet" ""
			(at 181.61 160.02 0)
			(effects
				(font
					(size 1.27 1.27)
					(thickness 0.15)
				)
				(justify left bottom)
				(hide yes)
			)
		)
		(property "Description" ""
			(at 172.72 147.32 0)
			(effects
				(font
					(size 1.27 1.27)
				)
				(hide yes)
			)
		)
		(property "Author" "Antmicro"
			(at 181.61 154.94 0)
			(effects
				(font
					(size 1.27 1.27)
					(thickness 0.15)
				)
				(justify left bottom)
				(hide yes)
			)
		)
		(property "License" "Apache-2.0"
			(at 181.61 157.48 0)
			(effects
				(font
					(size 1.27 1.27)
					(thickness 0.15)
				)
				(justify left bottom)
				(hide yes)
			)
		)
		(pin "1"
		)
		(instances
			(project "oculink-to-10gbe-adapter"
				(path ""
					(reference "#PWR0342")
					(unit 1)
				)
			)
		)
	)
	(symbol
		(lib_id "antmicroTVSDiodes:PESD5Z5_0F")
		(at 317.5 133.35 90)
		(mirror x)
		(unit 1)
		(exclude_from_sim no)
		(in_bom yes)
		(on_board yes)
		(dnp no)
		(property "Reference" "D13"
			(at 314.96 134.62 90)
			(effects
				(font
					(size 1.27 1.27)
					(thickness 0.15)
				)
				(justify left)
			)
		)
		(property "Value" "PESD5Z5_0F"
			(at 330.2 148.59 0)
			(effects
				(font
					(size 1.27 1.27)
					(thickness 0.15)
				)
				(justify left bottom)
				(hide yes)
			)
		)
		(property "Footprint" "antmicro-footprints:SOD-523"
			(at 322.58 148.59 0)
			(effects
				(font
					(size 1.27 1.27)
					(thickness 0.15)
				)
				(justify left bottom)
				(hide yes)
			)
		)
		(property "Datasheet" "https://assets.nexperia.com/documents/data-sheet/PESD5Z5_0.pdf"
			(at 325.12 148.59 0)
			(effects
				(font
					(size 1.27 1.27)
					(thickness 0.15)
				)
				(justify left bottom)
				(hide yes)
			)
		)
		(property "Description" "Unidirectional TVS, 30 kV,  SOD-523, 5 V, 89 pF"
			(at 337.82 148.59 0)
			(effects
				(font
					(size 1.27 1.27)
				)
				(justify left bottom)
				(hide yes)
			)
		)
		(property "Manufacturer" "Nexperia"
			(at 327.66 148.59 0)
			(effects
				(font
					(size 1.27 1.27)
					(thickness 0.15)
				)
				(justify left bottom)
				(hide yes)
			)
		)
		(property "MPN" "PESD5Z5.0F"
			(at 314.96 137.16 90)
			(effects
				(font
					(size 1.27 1.27)
					(thickness 0.15)
				)
				(justify left)
			)
		)
		(property "Author" "Antmicro"
			(at 332.74 148.59 0)
			(effects
				(font
					(size 1.27 1.27)
					(thickness 0.15)
				)
				(justify left bottom)
				(hide yes)
			)
		)
		(property "License" "Apache-2.0"
			(at 335.28 148.59 0)
			(effects
				(font
					(size 1.27 1.27)
					(thickness 0.15)
				)
				(justify left bottom)
				(hide yes)
			)
		)
		(pin "2"
		)
		(pin "1"
		)
		(instances
			(project "oculink-to-10gbe-adapter"
				(path ""
					(reference "D13")
					(unit 1)
				)
			)
		)
	)
	(symbol
		(lib_id "antmicropower:GND")
		(at 322.58 140.97 0)
		(unit 1)
		(exclude_from_sim no)
		(in_bom yes)
		(on_board yes)
		(dnp no)
		(property "Reference" "#PWR0303"
			(at 331.47 143.51 0)
			(effects
				(font
					(size 1.27 1.27)
					(thickness 0.15)
				)
				(justify left bottom)
				(hide yes)
			)
		)
		(property "Value" "GND"
			(at 322.58 144.78 0)
			(effects
				(font
					(size 1.27 1.27)
					(thickness 0.15)
				)
			)
		)
		(property "Footprint" ""
			(at 331.47 148.59 0)
			(effects
				(font
					(size 1.27 1.27)
					(thickness 0.15)
				)
				(justify left bottom)
				(hide yes)
			)
		)
		(property "Datasheet" ""
			(at 331.47 153.67 0)
			(effects
				(font
					(size 1.27 1.27)
					(thickness 0.15)
				)
				(justify left bottom)
				(hide yes)
			)
		)
		(property "Description" ""
			(at 322.58 140.97 0)
			(effects
				(font
					(size 1.27 1.27)
				)
				(hide yes)
			)
		)
		(property "Author" "Antmicro"
			(at 331.47 148.59 0)
			(effects
				(font
					(size 1.27 1.27)
					(thickness 0.15)
				)
				(justify left bottom)
				(hide yes)
			)
		)
		(property "License" "Apache-2.0"
			(at 331.47 151.13 0)
			(effects
				(font
					(size 1.27 1.27)
					(thickness 0.15)
				)
				(justify left bottom)
				(hide yes)
			)
		)
		(pin "1"
		)
		(instances
			(project "oculink-to-10gbe-adapter"
				(path ""
					(reference "#PWR0303")
					(unit 1)
				)
			)
		)
	)
	(symbol
		(lib_id "antmicroTemperatureSensorsAnalogandDigitalOutput:RT_NTC_10k_0402")
		(at 153.67 139.7 270)
		(unit 1)
		(exclude_from_sim no)
		(in_bom yes)
		(on_board yes)
		(dnp no)
		(fields_autoplaced yes)
		(property "Reference" "RT1"
			(at 156.21 140.9065 90)
			(effects
				(font
					(size 1.27 1.27)
					(thickness 0.15)
				)
				(justify left)
			)
		)
		(property "Value" "RT_NTC_10k_0402"
			(at 143.51 160.02 0)
			(effects
				(font
					(size 1.27 1.27)
					(thickness 0.15)
				)
				(justify left bottom)
				(hide yes)
			)
		)
		(property "Footprint" "antmicro-footprints:R_0402_1005Metric"
			(at 138.43 160.02 0)
			(effects
				(font
					(size 1.27 1.27)
					(thickness 0.15)
				)
				(justify left bottom)
				(hide yes)
			)
		)
		(property "Datasheet" "https://eu.mouser.com/datasheet/2/281/r44e-522712.pdf"
			(at 135.89 160.02 0)
			(effects
				(font
					(size 1.27 1.27)
					(thickness 0.15)
				)
				(justify left bottom)
				(hide yes)
			)
		)
		(property "Description" "10k NTC in 0402 package with 5V max voltage"
			(at 123.19 160.02 0)
			(effects
				(font
					(size 1.27 1.27)
				)
				(justify left bottom)
				(hide yes)
			)
		)
		(property "MPN" "NCP15XH103F03RC"
			(at 130.81 160.02 0)
			(effects
				(font
					(size 1.27 1.27)
				)
				(justify left bottom)
				(hide yes)
			)
		)
		(property "Manufacturer" "Murata"
			(at 133.35 160.02 0)
			(effects
				(font
					(size 1.27 1.27)
				)
				(justify left bottom)
				(hide yes)
			)
		)
		(property "License" "Apache-2.0"
			(at 125.73 160.02 0)
			(effects
				(font
					(size 1.27 1.27)
				)
				(justify left bottom)
				(hide yes)
			)
		)
		(property "Author" "Antmicro"
			(at 128.27 160.02 0)
			(effects
				(font
					(size 1.27 1.27)
				)
				(justify left bottom)
				(hide yes)
			)
		)
		(property "Val" "10k"
			(at 156.21 143.4464 90)
			(effects
				(font
					(size 1.27 1.27)
				)
				(justify left)
			)
		)
		(property "Voltage" "5V"
			(at 140.97 160.02 0)
			(effects
				(font
					(size 1.27 1.27)
				)
				(justify left bottom)
				(hide yes)
			)
		)
		(pin "1"
		)
		(pin "2"
		)
		(instances
			(project ""
				(path ""
					(reference "RT1")
					(unit 1)
				)
			)
		)
	)
	(symbol
		(lib_id "antmicropower:GND")
		(at 279.4 149.86 0)
		(unit 1)
		(exclude_from_sim no)
		(in_bom yes)
		(on_board yes)
		(dnp no)
		(property "Reference" "#PWR0340"
			(at 288.29 152.4 0)
			(effects
				(font
					(size 1.27 1.27)
					(thickness 0.15)
				)
				(justify left bottom)
				(hide yes)
			)
		)
		(property "Value" "GND"
			(at 279.4 153.67 0)
			(effects
				(font
					(size 1.27 1.27)
					(thickness 0.15)
				)
			)
		)
		(property "Footprint" ""
			(at 288.29 157.48 0)
			(effects
				(font
					(size 1.27 1.27)
					(thickness 0.15)
				)
				(justify left bottom)
				(hide yes)
			)
		)
		(property "Datasheet" ""
			(at 288.29 162.56 0)
			(effects
				(font
					(size 1.27 1.27)
					(thickness 0.15)
				)
				(justify left bottom)
				(hide yes)
			)
		)
		(property "Description" ""
			(at 279.4 149.86 0)
			(effects
				(font
					(size 1.27 1.27)
				)
				(hide yes)
			)
		)
		(property "Author" "Antmicro"
			(at 288.29 157.48 0)
			(effects
				(font
					(size 1.27 1.27)
					(thickness 0.15)
				)
				(justify left bottom)
				(hide yes)
			)
		)
		(property "License" "Apache-2.0"
			(at 288.29 160.02 0)
			(effects
				(font
					(size 1.27 1.27)
					(thickness 0.15)
				)
				(justify left bottom)
				(hide yes)
			)
		)
		(pin "1"
		)
		(instances
			(project "oculink-to-10gbe-adapter"
				(path ""
					(reference "#PWR0340")
					(unit 1)
				)
			)
		)
	)
	(symbol
		(lib_id "antmicroTestPoints:TP_0.75mm_SMD")
		(at 96.52 140.97 0)
		(unit 1)
		(exclude_from_sim no)
		(in_bom no)
		(on_board yes)
		(dnp no)
		(fields_autoplaced yes)
		(property "Reference" "TP26"
			(at 101.6 140.97 0)
			(effects
				(font
					(size 1.27 1.27)
					(thickness 0.15)
				)
				(justify left)
			)
		)
		(property "Value" "TP_0.75mm_SMD"
			(at 106.68 144.78 0)
			(effects
				(font
					(size 1.27 1.27)
					(thickness 0.15)
				)
				(justify left bottom)
				(hide yes)
			)
		)
		(property "Footprint" "antmicro-footprints:TP_SMD_0.75mm"
			(at 106.68 147.32 0)
			(effects
				(font
					(size 1.27 1.27)
					(thickness 0.15)
				)
				(justify left bottom)
				(hide yes)
			)
		)
		(property "Datasheet" ""
			(at 114.3 153.67 0)
			(effects
				(font
					(size 1.27 1.27)
					(thickness 0.15)
				)
				(justify left bottom)
				(hide yes)
			)
		)
		(property "Description" "SMT test point"
			(at 107.315 154.94 0)
			(effects
				(font
					(size 1.27 1.27)
				)
				(justify left bottom)
				(hide yes)
			)
		)
		(property "MPN" ""
			(at 107.315 152.4 0)
			(effects
				(font
					(size 1.27 1.27)
					(thickness 0.15)
				)
				(justify left bottom)
				(hide yes)
			)
		)
		(property "Manufacturer" ""
			(at 107.315 147.32 0)
			(effects
				(font
					(size 1.27 1.27)
					(thickness 0.15)
				)
				(justify left bottom)
				(hide yes)
			)
		)
		(property "Author" "Antmicro"
			(at 106.68 149.86 0)
			(effects
				(font
					(size 1.27 1.27)
					(thickness 0.15)
				)
				(justify left bottom)
				(hide yes)
			)
		)
		(property "License" "Apache-2.0"
			(at 106.68 152.4 0)
			(effects
				(font
					(size 1.27 1.27)
					(thickness 0.15)
				)
				(justify left bottom)
				(hide yes)
			)
		)
		(pin "1"
		)
		(instances
			(project ""
				(path ""
					(reference "TP26")
					(unit 1)
				)
			)
		)
	)
	(symbol
		(lib_id "antmicroCapacitors0402:C_10n_0402")
		(at 83.82 149.86 90)
		(unit 1)
		(exclude_from_sim no)
		(in_bom yes)
		(on_board yes)
		(dnp no)
		(fields_autoplaced yes)
		(property "Reference" "C210"
			(at 86.36 146.0436 90)
			(effects
				(font
					(size 1.27 1.27)
					(thickness 0.15)
				)
				(justify right)
			)
		)
		(property "Value" "C_10n_0402"
			(at 93.98 129.54 0)
			(effects
				(font
					(size 1.27 1.27)
					(thickness 0.15)
				)
				(justify left bottom)
				(hide yes)
			)
		)
		(property "Footprint" "antmicro-footprints:C_0402_1005Metric"
			(at 96.52 129.54 0)
			(effects
				(font
					(size 1.27 1.27)
					(thickness 0.15)
				)
				(justify left bottom)
				(hide yes)
			)
		)
		(property "Datasheet" "https://www.murata.com/products/productdetail?partno=GRM155R71H103KA88%23"
			(at 99.06 129.54 0)
			(effects
				(font
					(size 1.27 1.27)
					(thickness 0.15)
				)
				(justify left bottom)
				(hide yes)
			)
		)
		(property "Description" "SMD Multilayer Ceramic Capacitor, 10000 pF, 50 V, 0402 [1005 Metric], ± 10%, X7R, GRM Series"
			(at 116.84 129.54 0)
			(effects
				(font
					(size 1.27 1.27)
				)
				(justify left bottom)
				(hide yes)
			)
		)
		(property "MPN" "GRM155R71H103KA88D"
			(at 101.6 129.54 0)
			(effects
				(font
					(size 1.27 1.27)
					(thickness 0.15)
				)
				(justify left bottom)
				(hide yes)
			)
		)
		(property "Manufacturer" "Murata"
			(at 104.14 129.54 0)
			(effects
				(font
					(size 1.27 1.27)
					(thickness 0.15)
				)
				(justify left bottom)
				(hide yes)
			)
		)
		(property "License" "Apache-2.0"
			(at 106.68 129.54 0)
			(effects
				(font
					(size 1.27 1.27)
					(thickness 0.15)
				)
				(justify left bottom)
				(hide yes)
			)
		)
		(property "Author" "Antmicro"
			(at 109.22 129.54 0)
			(effects
				(font
					(size 1.27 1.27)
					(thickness 0.15)
				)
				(justify left bottom)
				(hide yes)
			)
		)
		(property "Val" "10n"
			(at 86.36 148.5836 90)
			(effects
				(font
					(size 1.27 1.27)
					(thickness 0.15)
				)
				(justify right)
			)
		)
		(property "Voltage" "50V"
			(at 111.76 129.54 0)
			(effects
				(font
					(size 1.27 1.27)
				)
				(justify left bottom)
				(hide yes)
			)
		)
		(property "Dielectric" "X7R"
			(at 114.3 129.54 0)
			(effects
				(font
					(size 1.27 1.27)
				)
				(justify left bottom)
				(hide yes)
			)
		)
		(pin "1"
		)
		(pin "2"
		)
		(instances
			(project ""
				(path ""
					(reference "C210")
					(unit 1)
				)
			)
		)
	)
	(symbol
		(lib_id "antmicropower:GND")
		(at 54.61 151.13 0)
		(unit 1)
		(exclude_from_sim no)
		(in_bom yes)
		(on_board yes)
		(dnp no)
		(property "Reference" "#PWR0361"
			(at 63.5 153.67 0)
			(effects
				(font
					(size 1.27 1.27)
					(thickness 0.15)
				)
				(justify left bottom)
				(hide yes)
			)
		)
		(property "Value" "GND"
			(at 54.61 154.94 0)
			(effects
				(font
					(size 1.27 1.27)
					(thickness 0.15)
				)
			)
		)
		(property "Footprint" ""
			(at 63.5 158.75 0)
			(effects
				(font
					(size 1.27 1.27)
					(thickness 0.15)
				)
				(justify left bottom)
				(hide yes)
			)
		)
		(property "Datasheet" ""
			(at 63.5 163.83 0)
			(effects
				(font
					(size 1.27 1.27)
					(thickness 0.15)
				)
				(justify left bottom)
				(hide yes)
			)
		)
		(property "Description" ""
			(at 54.61 151.13 0)
			(effects
				(font
					(size 1.27 1.27)
				)
				(hide yes)
			)
		)
		(property "Author" "Antmicro"
			(at 63.5 158.75 0)
			(effects
				(font
					(size 1.27 1.27)
					(thickness 0.15)
				)
				(justify left bottom)
				(hide yes)
			)
		)
		(property "License" "Apache-2.0"
			(at 63.5 161.29 0)
			(effects
				(font
					(size 1.27 1.27)
					(thickness 0.15)
				)
				(justify left bottom)
				(hide yes)
			)
		)
		(pin "1"
		)
		(instances
			(project "oculink-to-10gbe-adapter"
				(path ""
					(reference "#PWR0361")
					(unit 1)
				)
			)
		)
	)
	(symbol
		(lib_id "antmicropower:GND")
		(at 317.5 140.97 0)
		(unit 1)
		(exclude_from_sim no)
		(in_bom yes)
		(on_board yes)
		(dnp no)
		(property "Reference" "#PWR0302"
			(at 326.39 143.51 0)
			(effects
				(font
					(size 1.27 1.27)
					(thickness 0.15)
				)
				(justify left bottom)
				(hide yes)
			)
		)
		(property "Value" "GND"
			(at 317.5 144.78 0)
			(effects
				(font
					(size 1.27 1.27)
					(thickness 0.15)
				)
			)
		)
		(property "Footprint" ""
			(at 326.39 148.59 0)
			(effects
				(font
					(size 1.27 1.27)
					(thickness 0.15)
				)
				(justify left bottom)
				(hide yes)
			)
		)
		(property "Datasheet" ""
			(at 326.39 153.67 0)
			(effects
				(font
					(size 1.27 1.27)
					(thickness 0.15)
				)
				(justify left bottom)
				(hide yes)
			)
		)
		(property "Description" ""
			(at 317.5 140.97 0)
			(effects
				(font
					(size 1.27 1.27)
				)
				(hide yes)
			)
		)
		(property "Author" "Antmicro"
			(at 326.39 148.59 0)
			(effects
				(font
					(size 1.27 1.27)
					(thickness 0.15)
				)
				(justify left bottom)
				(hide yes)
			)
		)
		(property "License" "Apache-2.0"
			(at 326.39 151.13 0)
			(effects
				(font
					(size 1.27 1.27)
					(thickness 0.15)
				)
				(justify left bottom)
				(hide yes)
			)
		)
		(pin "1"
		)
		(instances
			(project "oculink-to-10gbe-adapter"
				(path ""
					(reference "#PWR0302")
					(unit 1)
				)
			)
		)
	)
	(symbol
		(lib_id "antmicropower:GND")
		(at 95.25 151.13 0)
		(unit 1)
		(exclude_from_sim no)
		(in_bom yes)
		(on_board yes)
		(dnp no)
		(property "Reference" "#PWR0360"
			(at 104.14 153.67 0)
			(effects
				(font
					(size 1.27 1.27)
					(thickness 0.15)
				)
				(justify left bottom)
				(hide yes)
			)
		)
		(property "Value" "GND"
			(at 95.25 154.94 0)
			(effects
				(font
					(size 1.27 1.27)
					(thickness 0.15)
				)
			)
		)
		(property "Footprint" ""
			(at 104.14 158.75 0)
			(effects
				(font
					(size 1.27 1.27)
					(thickness 0.15)
				)
				(justify left bottom)
				(hide yes)
			)
		)
		(property "Datasheet" ""
			(at 104.14 163.83 0)
			(effects
				(font
					(size 1.27 1.27)
					(thickness 0.15)
				)
				(justify left bottom)
				(hide yes)
			)
		)
		(property "Description" ""
			(at 95.25 151.13 0)
			(effects
				(font
					(size 1.27 1.27)
				)
				(hide yes)
			)
		)
		(property "Author" "Antmicro"
			(at 104.14 158.75 0)
			(effects
				(font
					(size 1.27 1.27)
					(thickness 0.15)
				)
				(justify left bottom)
				(hide yes)
			)
		)
		(property "License" "Apache-2.0"
			(at 104.14 161.29 0)
			(effects
				(font
					(size 1.27 1.27)
					(thickness 0.15)
				)
				(justify left bottom)
				(hide yes)
			)
		)
		(pin "1"
		)
		(instances
			(project "oculink-to-10gbe-adapter"
				(path ""
					(reference "#PWR0360")
					(unit 1)
				)
			)
		)
	)
	(symbol
		(lib_id "antmicroCapacitors0402:C_1u_25V_0402")
		(at 172.72 144.78 90)
		(unit 1)
		(exclude_from_sim no)
		(in_bom yes)
		(on_board yes)
		(dnp no)
		(fields_autoplaced yes)
		(property "Reference" "C209"
			(at 175.26 140.9636 90)
			(effects
				(font
					(size 1.27 1.27)
					(thickness 0.15)
				)
				(justify right)
			)
		)
		(property "Value" "C_1u_25V_0402"
			(at 182.88 124.46 0)
			(effects
				(font
					(size 1.27 1.27)
					(thickness 0.15)
				)
				(justify left bottom)
				(hide yes)
			)
		)
		(property "Footprint" "antmicro-footprints:C_0402_1005Metric"
			(at 185.42 124.46 0)
			(effects
				(font
					(size 1.27 1.27)
					(thickness 0.15)
				)
				(justify left bottom)
				(hide yes)
			)
		)
		(property "Datasheet" "https://www.murata.com/products/productdetail?partno=GRM155R61E105KE11%23"
			(at 187.96 124.46 0)
			(effects
				(font
					(size 1.27 1.27)
					(thickness 0.15)
				)
				(justify left bottom)
				(hide yes)
			)
		)
		(property "Description" "SMD Multilayer Ceramic Capacitor, 1 µF, 25 V, 0402 [1005 Metric], ± 10%, X5R, GRM Series"
			(at 205.74 124.46 0)
			(effects
				(font
					(size 1.27 1.27)
				)
				(justify left bottom)
				(hide yes)
			)
		)
		(property "MPN" "GRM155R61E105KE11J"
			(at 190.5 124.46 0)
			(effects
				(font
					(size 1.27 1.27)
					(thickness 0.15)
				)
				(justify left bottom)
				(hide yes)
			)
		)
		(property "Manufacturer" "Murata"
			(at 193.04 124.46 0)
			(effects
				(font
					(size 1.27 1.27)
					(thickness 0.15)
				)
				(justify left bottom)
				(hide yes)
			)
		)
		(property "License" "Apache-2.0"
			(at 195.58 124.46 0)
			(effects
				(font
					(size 1.27 1.27)
					(thickness 0.15)
				)
				(justify left bottom)
				(hide yes)
			)
		)
		(property "Author" "Antmicro"
			(at 198.12 124.46 0)
			(effects
				(font
					(size 1.27 1.27)
					(thickness 0.15)
				)
				(justify left bottom)
				(hide yes)
			)
		)
		(property "Val" "1u"
			(at 175.26 143.5036 90)
			(effects
				(font
					(size 1.27 1.27)
					(thickness 0.15)
				)
				(justify right)
			)
		)
		(property "Voltage" "25V"
			(at 200.66 124.46 0)
			(effects
				(font
					(size 1.27 1.27)
				)
				(justify left bottom)
				(hide yes)
			)
		)
		(property "Dielectric" "X5R"
			(at 203.2 124.46 0)
			(effects
				(font
					(size 1.27 1.27)
				)
				(justify left bottom)
				(hide yes)
			)
		)
		(pin "1"
		)
		(pin "2"
		)
		(instances
			(project ""
				(path ""
					(reference "C209")
					(unit 1)
				)
			)
		)
	)
	(symbol
		(lib_id "antmicroResistors0402:R_0R_0402")
		(at 193.04 181.61 90)
		(unit 1)
		(exclude_from_sim no)
		(in_bom yes)
		(on_board yes)
		(dnp no)
		(property "Reference" "R176"
			(at 194.31 177.8 90)
			(effects
				(font
					(size 1.27 1.27)
					(thickness 0.15)
				)
				(justify right)
			)
		)
		(property "Value" "R_0R_0402"
			(at 205.74 161.29 0)
			(effects
				(font
					(size 1.27 1.27)
					(thickness 0.15)
				)
				(justify left bottom)
				(hide yes)
			)
		)
		(property "Footprint" "antmicro-footprints:R_0402_1005Metric"
			(at 208.28 161.29 0)
			(effects
				(font
					(size 1.27 1.27)
					(thickness 0.15)
				)
				(justify left bottom)
				(hide yes)
			)
		)
		(property "Datasheet" "https://industrial.panasonic.com/cdbs/www-data/pdf/RDA0000/AOA0000C301.pdf"
			(at 210.82 161.29 0)
			(effects
				(font
					(size 1.27 1.27)
					(thickness 0.15)
				)
				(justify left bottom)
				(hide yes)
			)
		)
		(property "Description" "SMD Chip Resistor, Jumper, 0 ohm, 100 mW, 0402 [1005 Metric], Thick Film, General Purpose"
			(at 226.06 161.29 0)
			(effects
				(font
					(size 1.27 1.27)
				)
				(justify left bottom)
				(hide yes)
			)
		)
		(property "MPN" "ERJ2GE0R00X"
			(at 213.36 161.29 0)
			(effects
				(font
					(size 1.27 1.27)
					(thickness 0.15)
				)
				(justify left bottom)
				(hide yes)
			)
		)
		(property "Manufacturer" "Panasonic"
			(at 215.9 161.29 0)
			(effects
				(font
					(size 1.27 1.27)
					(thickness 0.15)
				)
				(justify left bottom)
				(hide yes)
			)
		)
		(property "License" "Apache-2.0"
			(at 218.44 161.29 0)
			(effects
				(font
					(size 1.27 1.27)
					(thickness 0.15)
				)
				(justify left bottom)
				(hide yes)
			)
		)
		(property "Author" "Antmicro"
			(at 220.98 161.29 0)
			(effects
				(font
					(size 1.27 1.27)
					(thickness 0.15)
				)
				(justify left bottom)
				(hide yes)
			)
		)
		(property "Val" "0R"
			(at 194.31 180.34 90)
			(effects
				(font
					(size 1.27 1.27)
					(thickness 0.15)
				)
				(justify right)
			)
		)
		(property "Tolerance" "~"
			(at 203.2 161.29 0)
			(effects
				(font
					(size 1.27 1.27)
				)
				(justify left bottom)
				(hide yes)
			)
		)
		(property "Current" "1A"
			(at 223.52 161.29 0)
			(effects
				(font
					(size 1.27 1.27)
					(thickness 0.15)
				)
				(justify left bottom)
				(hide yes)
			)
		)
		(pin "2"
		)
		(pin "1"
		)
		(instances
			(project ""
				(path ""
					(reference "R176")
					(unit 1)
				)
			)
		)
	)
	(symbol
		(lib_id "antmicroResistors0402:R_6k04_0.1%_0402")
		(at 153.67 132.08 90)
		(unit 1)
		(exclude_from_sim no)
		(in_bom yes)
		(on_board yes)
		(dnp no)
		(fields_autoplaced yes)
		(property "Reference" "R182"
			(at 156.21 127 90)
			(effects
				(font
					(size 1.27 1.27)
					(thickness 0.15)
				)
				(justify right)
			)
		)
		(property "Value" "R_6k04_0.1%_0402"
			(at 166.37 111.76 0)
			(effects
				(font
					(size 1.27 1.27)
					(thickness 0.15)
				)
				(justify left bottom)
				(hide yes)
			)
		)
		(property "Footprint" "antmicro-footprints:R_0402_1005Metric"
			(at 168.91 111.76 0)
			(effects
				(font
					(size 1.27 1.27)
					(thickness 0.15)
				)
				(justify left bottom)
				(hide yes)
			)
		)
		(property "Datasheet" "https://www.vishay.com/docs/28758/tnpw_e3.pdf"
			(at 171.45 111.76 0)
			(effects
				(font
					(size 1.27 1.27)
					(thickness 0.15)
				)
				(justify left bottom)
				(hide yes)
			)
		)
		(property "Description" "SMD Chip Resistor, 6.49 kohm, ± 1%, 62.5 mW, 0402 [1005 Metric], Thick Film, General Purpose"
			(at 184.15 111.76 0)
			(effects
				(font
					(size 1.27 1.27)
				)
				(justify left bottom)
				(hide yes)
			)
		)
		(property "MPN" "TNPW04026K04BEED"
			(at 173.99 111.76 0)
			(effects
				(font
					(size 1.27 1.27)
					(thickness 0.15)
				)
				(justify left bottom)
				(hide yes)
			)
		)
		(property "Manufacturer" "Vishay"
			(at 176.53 111.76 0)
			(effects
				(font
					(size 1.27 1.27)
					(thickness 0.15)
				)
				(justify left bottom)
				(hide yes)
			)
		)
		(property "License" "Apache-2.0"
			(at 179.07 111.76 0)
			(effects
				(font
					(size 1.27 1.27)
					(thickness 0.15)
				)
				(justify left bottom)
				(hide yes)
			)
		)
		(property "Author" "Antmicro"
			(at 181.61 111.76 0)
			(effects
				(font
					(size 1.27 1.27)
					(thickness 0.15)
				)
				(justify left bottom)
				(hide yes)
			)
		)
		(property "Val" "6k04"
			(at 156.21 129.54 90)
			(effects
				(font
					(size 1.27 1.27)
					(thickness 0.15)
				)
				(justify right)
			)
		)
		(property "Tolerance" "0.1%"
			(at 156.21 132.0799 90)
			(effects
				(font
					(size 1.27 1.27)
				)
				(justify right)
			)
		)
		(pin "2"
		)
		(pin "1"
		)
		(instances
			(project ""
				(path ""
					(reference "R182")
					(unit 1)
				)
			)
		)
	)
	(symbol
		(lib_id "antmicroTemperatureSensorsAnalogandDigitalOutput:MAX31740ATA+T")
		(at 193.04 132.08 0)
		(unit 1)
		(exclude_from_sim no)
		(in_bom yes)
		(on_board yes)
		(dnp no)
		(fields_autoplaced yes)
		(property "Reference" "U14"
			(at 204.47 124.46 0)
			(effects
				(font
					(size 1.27 1.27)
					(thickness 0.15)
				)
			)
		)
		(property "Value" "MAX31740ATA+T"
			(at 228.6 139.7 0)
			(effects
				(font
					(size 1.27 1.27)
					(thickness 0.15)
				)
				(justify left bottom)
				(hide yes)
			)
		)
		(property "Footprint" "antmicro-footprints:TDFN-8-1EP_2x3x0.75mm_P0.5mm_EP1.75x1.63mm"
			(at 228.6 142.24 0)
			(effects
				(font
					(size 1.27 1.27)
					(thickness 0.15)
				)
				(justify left bottom)
				(hide yes)
			)
		)
		(property "Datasheet" "https://www.analog.com/media/en/technical-documentation/data-sheets/max31740.pdf"
			(at 228.6 144.78 0)
			(effects
				(font
					(size 1.27 1.27)
					(thickness 0.15)
				)
				(justify left bottom)
				(hide yes)
			)
		)
		(property "Description" "Pwm fan speed controller, temperature measurement, Control speed of 2-, 3-, 4- Wire Fans"
			(at 228.6 154.94 0)
			(effects
				(font
					(size 1.27 1.27)
				)
				(justify left bottom)
				(hide yes)
			)
		)
		(property "MPN" "MAX31740ATA+T"
			(at 204.47 127 0)
			(effects
				(font
					(size 1.27 1.27)
					(thickness 0.15)
				)
			)
		)
		(property "Manufacturer" "Analog Devices"
			(at 228.6 147.32 0)
			(effects
				(font
					(size 1.27 1.27)
					(thickness 0.15)
				)
				(justify left bottom)
				(hide yes)
			)
		)
		(property "Author" "Antmicro"
			(at 228.6 149.86 0)
			(effects
				(font
					(size 1.27 1.27)
					(thickness 0.15)
				)
				(justify left bottom)
				(hide yes)
			)
		)
		(property "License" "Apache-2.0"
			(at 228.6 152.4 0)
			(effects
				(font
					(size 1.27 1.27)
					(thickness 0.15)
				)
				(justify left bottom)
				(hide yes)
			)
		)
		(pin "6"
		)
		(pin "9"
		)
		(pin "7"
		)
		(pin "8"
		)
		(pin "3"
		)
		(pin "4"
		)
		(pin "5"
		)
		(pin "1"
		)
		(pin "2"
		)
		(instances
			(project "oculink-to-10gbe-adapter"
				(path ""
					(reference "U14")
					(unit 1)
				)
			)
		)
	)
	(symbol
		(lib_id "antmicropower:GND")
		(at 180.34 184.15 0)
		(unit 1)
		(exclude_from_sim no)
		(in_bom yes)
		(on_board yes)
		(dnp no)
		(property "Reference" "#PWR0346"
			(at 189.23 186.69 0)
			(effects
				(font
					(size 1.27 1.27)
					(thickness 0.15)
				)
				(justify left bottom)
				(hide yes)
			)
		)
		(property "Value" "GND"
			(at 180.34 187.96 0)
			(effects
				(font
					(size 1.27 1.27)
					(thickness 0.15)
				)
			)
		)
		(property "Footprint" ""
			(at 189.23 191.77 0)
			(effects
				(font
					(size 1.27 1.27)
					(thickness 0.15)
				)
				(justify left bottom)
				(hide yes)
			)
		)
		(property "Datasheet" ""
			(at 189.23 196.85 0)
			(effects
				(font
					(size 1.27 1.27)
					(thickness 0.15)
				)
				(justify left bottom)
				(hide yes)
			)
		)
		(property "Description" ""
			(at 180.34 184.15 0)
			(effects
				(font
					(size 1.27 1.27)
				)
				(hide yes)
			)
		)
		(property "Author" "Antmicro"
			(at 189.23 191.77 0)
			(effects
				(font
					(size 1.27 1.27)
					(thickness 0.15)
				)
				(justify left bottom)
				(hide yes)
			)
		)
		(property "License" "Apache-2.0"
			(at 189.23 194.31 0)
			(effects
				(font
					(size 1.27 1.27)
					(thickness 0.15)
				)
				(justify left bottom)
				(hide yes)
			)
		)
		(pin "1"
		)
		(instances
			(project "oculink-to-10gbe-adapter"
				(path ""
					(reference "#PWR0346")
					(unit 1)
				)
			)
		)
	)
	(symbol
		(lib_id "antmicropower:GND")
		(at 237.49 149.86 0)
		(unit 1)
		(exclude_from_sim no)
		(in_bom yes)
		(on_board yes)
		(dnp no)
		(property "Reference" "#PWR0349"
			(at 246.38 152.4 0)
			(effects
				(font
					(size 1.27 1.27)
					(thickness 0.15)
				)
				(justify left bottom)
				(hide yes)
			)
		)
		(property "Value" "GND"
			(at 237.49 153.67 0)
			(effects
				(font
					(size 1.27 1.27)
					(thickness 0.15)
				)
			)
		)
		(property "Footprint" ""
			(at 246.38 157.48 0)
			(effects
				(font
					(size 1.27 1.27)
					(thickness 0.15)
				)
				(justify left bottom)
				(hide yes)
			)
		)
		(property "Datasheet" ""
			(at 246.38 162.56 0)
			(effects
				(font
					(size 1.27 1.27)
					(thickness 0.15)
				)
				(justify left bottom)
				(hide yes)
			)
		)
		(property "Description" ""
			(at 237.49 149.86 0)
			(effects
				(font
					(size 1.27 1.27)
				)
				(hide yes)
			)
		)
		(property "Author" "Antmicro"
			(at 246.38 157.48 0)
			(effects
				(font
					(size 1.27 1.27)
					(thickness 0.15)
				)
				(justify left bottom)
				(hide yes)
			)
		)
		(property "License" "Apache-2.0"
			(at 246.38 160.02 0)
			(effects
				(font
					(size 1.27 1.27)
					(thickness 0.15)
				)
				(justify left bottom)
				(hide yes)
			)
		)
		(pin "1"
		)
		(instances
			(project "oculink-to-10gbe-adapter"
				(path ""
					(reference "#PWR0349")
					(unit 1)
				)
			)
		)
	)
	(symbol
		(lib_id "antmicroPMICVoltageRegulatorsLinear:LP2985IM5X-5.0_SOT")
		(at 62.23 140.97 0)
		(unit 1)
		(exclude_from_sim no)
		(in_bom yes)
		(on_board yes)
		(dnp no)
		(fields_autoplaced yes)
		(property "Reference" "U6"
			(at 69.215 133.35 0)
			(effects
				(font
					(size 1.27 1.27)
					(thickness 0.15)
				)
			)
		)
		(property "Value" "LP2985IM5X-5.0_SOT"
			(at 95.25 148.59 0)
			(effects
				(font
					(size 1.27 1.27)
					(thickness 0.15)
				)
				(justify left bottom)
				(hide yes)
			)
		)
		(property "Footprint" "antmicro-footprints:SOT-23-5"
			(at 95.25 151.13 0)
			(effects
				(font
					(size 1.27 1.27)
					(thickness 0.15)
				)
				(justify left bottom)
				(hide yes)
			)
		)
		(property "Datasheet" "https://www.ti.com/lit/ds/symlink/lp2985-n.pdf?ts=1705246249323&ref_url=https%253A%252F%252Fwww.mouser.se%252F"
			(at 95.25 153.67 0)
			(effects
				(font
					(size 1.27 1.27)
					(thickness 0.15)
				)
				(justify left bottom)
				(hide yes)
			)
		)
		(property "Description" "LDO voltage regulator 150-mA, 16-V, low-dropout voltage regulator with enable 5-SOT-23"
			(at 95.25 163.83 0)
			(effects
				(font
					(size 1.27 1.27)
				)
				(justify left bottom)
				(hide yes)
			)
		)
		(property "MPN" "LP2985IM5X-5.0/NOPB"
			(at 69.215 135.89 0)
			(effects
				(font
					(size 1.27 1.27)
					(thickness 0.15)
				)
			)
		)
		(property "Manufacturer" "Texas Instruments"
			(at 95.25 156.21 0)
			(effects
				(font
					(size 1.27 1.27)
					(thickness 0.15)
				)
				(justify left bottom)
				(hide yes)
			)
		)
		(property "Author" "Antmicro"
			(at 95.25 158.75 0)
			(effects
				(font
					(size 1.27 1.27)
					(thickness 0.15)
				)
				(justify left bottom)
				(hide yes)
			)
		)
		(property "License" "Apache-2.0"
			(at 95.25 161.29 0)
			(effects
				(font
					(size 1.27 1.27)
					(thickness 0.15)
				)
				(justify left bottom)
				(hide yes)
			)
		)
		(pin "3"
		)
		(pin "1"
		)
		(pin "5"
		)
		(pin "2"
		)
		(pin "4"
		)
		(instances
			(project "oculink-to-10gbe-adapter"
				(path ""
					(reference "U6")
					(unit 1)
				)
			)
		)
	)
	(symbol
		(lib_id "antmicropower:GND")
		(at 78.74 151.13 0)
		(unit 1)
		(exclude_from_sim no)
		(in_bom yes)
		(on_board yes)
		(dnp no)
		(property "Reference" "#PWR0358"
			(at 87.63 153.67 0)
			(effects
				(font
					(size 1.27 1.27)
					(thickness 0.15)
				)
				(justify left bottom)
				(hide yes)
			)
		)
		(property "Value" "GND"
			(at 78.74 154.94 0)
			(effects
				(font
					(size 1.27 1.27)
					(thickness 0.15)
				)
			)
		)
		(property "Footprint" ""
			(at 87.63 158.75 0)
			(effects
				(font
					(size 1.27 1.27)
					(thickness 0.15)
				)
				(justify left bottom)
				(hide yes)
			)
		)
		(property "Datasheet" ""
			(at 87.63 163.83 0)
			(effects
				(font
					(size 1.27 1.27)
					(thickness 0.15)
				)
				(justify left bottom)
				(hide yes)
			)
		)
		(property "Description" ""
			(at 78.74 151.13 0)
			(effects
				(font
					(size 1.27 1.27)
				)
				(hide yes)
			)
		)
		(property "Author" "Antmicro"
			(at 87.63 158.75 0)
			(effects
				(font
					(size 1.27 1.27)
					(thickness 0.15)
				)
				(justify left bottom)
				(hide yes)
			)
		)
		(property "License" "Apache-2.0"
			(at 87.63 161.29 0)
			(effects
				(font
					(size 1.27 1.27)
					(thickness 0.15)
				)
				(justify left bottom)
				(hide yes)
			)
		)
		(pin "1"
		)
		(instances
			(project "oculink-to-10gbe-adapter"
				(path ""
					(reference "#PWR0358")
					(unit 1)
				)
			)
		)
	)
	(symbol
		(lib_id "antmicropower:GND")
		(at 218.44 149.86 0)
		(unit 1)
		(exclude_from_sim no)
		(in_bom yes)
		(on_board yes)
		(dnp no)
		(property "Reference" "#PWR0343"
			(at 227.33 152.4 0)
			(effects
				(font
					(size 1.27 1.27)
					(thickness 0.15)
				)
				(justify left bottom)
				(hide yes)
			)
		)
		(property "Value" "GND"
			(at 218.44 153.67 0)
			(effects
				(font
					(size 1.27 1.27)
					(thickness 0.15)
				)
			)
		)
		(property "Footprint" ""
			(at 227.33 157.48 0)
			(effects
				(font
					(size 1.27 1.27)
					(thickness 0.15)
				)
				(justify left bottom)
				(hide yes)
			)
		)
		(property "Datasheet" ""
			(at 227.33 162.56 0)
			(effects
				(font
					(size 1.27 1.27)
					(thickness 0.15)
				)
				(justify left bottom)
				(hide yes)
			)
		)
		(property "Description" ""
			(at 218.44 149.86 0)
			(effects
				(font
					(size 1.27 1.27)
				)
				(hide yes)
			)
		)
		(property "Author" "Antmicro"
			(at 227.33 157.48 0)
			(effects
				(font
					(size 1.27 1.27)
					(thickness 0.15)
				)
				(justify left bottom)
				(hide yes)
			)
		)
		(property "License" "Apache-2.0"
			(at 227.33 160.02 0)
			(effects
				(font
					(size 1.27 1.27)
					(thickness 0.15)
				)
				(justify left bottom)
				(hide yes)
			)
		)
		(pin "1"
		)
		(instances
			(project "oculink-to-10gbe-adapter"
				(path ""
					(reference "#PWR0343")
					(unit 1)
				)
			)
		)
	)
	(symbol
		(lib_id "antmicropower:VCC")
		(at 279.4 116.84 0)
		(unit 1)
		(exclude_from_sim no)
		(in_bom yes)
		(on_board yes)
		(dnp no)
		(property "Reference" "#PWR0345"
			(at 279.4 120.65 0)
			(effects
				(font
					(size 1.27 1.27)
				)
				(hide yes)
			)
		)
		(property "Value" "VCC"
			(at 279.4 113.03 0)
			(effects
				(font
					(size 1.27 1.27)
				)
			)
		)
		(property "Footprint" ""
			(at 279.4 116.84 0)
			(effects
				(font
					(size 1.27 1.27)
				)
				(hide yes)
			)
		)
		(property "Datasheet" ""
			(at 279.4 116.84 0)
			(effects
				(font
					(size 1.27 1.27)
				)
				(hide yes)
			)
		)
		(property "Description" ""
			(at 279.4 123.19 0)
			(effects
				(font
					(size 1.27 1.27)
				)
				(justify left bottom)
				(hide yes)
			)
		)
		(pin "1"
		)
		(instances
			(project "oculink-to-10gbe-adapter"
				(path ""
					(reference "#PWR0345")
					(unit 1)
				)
			)
		)
	)
	(symbol
		(lib_id "antmicropower:GND")
		(at 153.67 147.32 0)
		(unit 1)
		(exclude_from_sim no)
		(in_bom yes)
		(on_board yes)
		(dnp no)
		(property "Reference" "#PWR0341"
			(at 162.56 149.86 0)
			(effects
				(font
					(size 1.27 1.27)
					(thickness 0.15)
				)
				(justify left bottom)
				(hide yes)
			)
		)
		(property "Value" "GND"
			(at 153.67 151.13 0)
			(effects
				(font
					(size 1.27 1.27)
					(thickness 0.15)
				)
			)
		)
		(property "Footprint" ""
			(at 162.56 154.94 0)
			(effects
				(font
					(size 1.27 1.27)
					(thickness 0.15)
				)
				(justify left bottom)
				(hide yes)
			)
		)
		(property "Datasheet" ""
			(at 162.56 160.02 0)
			(effects
				(font
					(size 1.27 1.27)
					(thickness 0.15)
				)
				(justify left bottom)
				(hide yes)
			)
		)
		(property "Description" ""
			(at 153.67 147.32 0)
			(effects
				(font
					(size 1.27 1.27)
				)
				(hide yes)
			)
		)
		(property "Author" "Antmicro"
			(at 162.56 154.94 0)
			(effects
				(font
					(size 1.27 1.27)
					(thickness 0.15)
				)
				(justify left bottom)
				(hide yes)
			)
		)
		(property "License" "Apache-2.0"
			(at 162.56 157.48 0)
			(effects
				(font
					(size 1.27 1.27)
					(thickness 0.15)
				)
				(justify left bottom)
				(hide yes)
			)
		)
		(pin "1"
		)
		(instances
			(project "oculink-to-10gbe-adapter"
				(path ""
					(reference "#PWR0341")
					(unit 1)
				)
			)
		)
	)
	(symbol
		(lib_id "antmicroWire2BoardConnectors:Molex_KK_1x4_0470531000")
		(at 281.94 139.7 0)
		(mirror x)
		(unit 1)
		(exclude_from_sim no)
		(in_bom yes)
		(on_board yes)
		(dnp no)
		(property "Reference" "J8"
			(at 288.29 137.16 0)
			(effects
				(font
					(size 1.27 1.27)
					(thickness 0.15)
				)
				(justify left)
			)
		)
		(property "Value" "Molex_KK_1x4_0470531000"
			(at 302.26 129.54 0)
			(effects
				(font
					(size 1.27 1.27)
					(thickness 0.15)
				)
				(justify left bottom)
				(hide yes)
			)
		)
		(property "Footprint" "antmicro-footprints:Conn_Molex_KK_1x4_0470531000"
			(at 302.26 127 0)
			(effects
				(font
					(size 1.27 1.27)
					(thickness 0.15)
				)
				(justify left bottom)
				(hide yes)
			)
		)
		(property "Datasheet" "https://tools.molex.com/pdm_docs/sd/470531000_sd.pdf"
			(at 302.26 124.46 0)
			(effects
				(font
					(size 1.27 1.27)
					(thickness 0.15)
				)
				(justify left bottom)
				(hide yes)
			)
		)
		(property "Description" "Connector Header, THT,  4x1"
			(at 302.26 114.3 0)
			(effects
				(font
					(size 1.27 1.27)
				)
				(justify left bottom)
				(hide yes)
			)
		)
		(property "MPN" "0470531000"
			(at 288.29 134.62 0)
			(effects
				(font
					(size 1.27 1.27)
					(thickness 0.15)
				)
				(justify left)
			)
		)
		(property "Manufacturer" "Molex"
			(at 302.26 121.92 0)
			(effects
				(font
					(size 1.27 1.27)
					(thickness 0.15)
				)
				(justify left bottom)
				(hide yes)
			)
		)
		(property "Author" "Antmicro"
			(at 302.26 119.38 0)
			(effects
				(font
					(size 1.27 1.27)
					(thickness 0.15)
				)
				(justify left bottom)
				(hide yes)
			)
		)
		(property "License" "Apache-2.0"
			(at 302.26 116.84 0)
			(effects
				(font
					(size 1.27 1.27)
					(thickness 0.15)
				)
				(justify left bottom)
				(hide yes)
			)
		)
		(pin "2"
		)
		(pin "1"
		)
		(pin "3"
		)
		(pin "4"
		)
		(instances
			(project "oculink-to-10gbe-adapter"
				(path ""
					(reference "J8")
					(unit 1)
				)
			)
		)
	)
	(symbol
		(lib_id "antmicroResistors0402:R_10k_0402")
		(at 163.83 137.16 0)
		(unit 1)
		(exclude_from_sim no)
		(in_bom yes)
		(on_board yes)
		(dnp no)
		(property "Reference" "R175"
			(at 166.37 134.62 0)
			(effects
				(font
					(size 1.27 1.27)
					(thickness 0.15)
				)
			)
		)
		(property "Value" "R_10k_0402"
			(at 184.15 149.86 0)
			(effects
				(font
					(size 1.27 1.27)
					(thickness 0.15)
				)
				(justify left bottom)
				(hide yes)
			)
		)
		(property "Footprint" "antmicro-footprints:R_0402_1005Metric"
			(at 184.15 152.4 0)
			(effects
				(font
					(size 1.27 1.27)
					(thickness 0.15)
				)
				(justify left bottom)
				(hide yes)
			)
		)
		(property "Datasheet" "https://www.bourns.com/docs/product-datasheets/cr.pdf"
			(at 184.15 154.94 0)
			(effects
				(font
					(size 1.27 1.27)
					(thickness 0.15)
				)
				(justify left bottom)
				(hide yes)
			)
		)
		(property "Description" "SMD Chip Resistor, 10 kohm, ± 1%, 62.5 mW, 0402 [1005 Metric], Thick Film, General Purpose"
			(at 184.15 167.64 0)
			(effects
				(font
					(size 1.27 1.27)
				)
				(justify left bottom)
				(hide yes)
			)
		)
		(property "MPN" "CR0402-FX-1002GLF"
			(at 184.15 157.48 0)
			(effects
				(font
					(size 1.27 1.27)
					(thickness 0.15)
				)
				(justify left bottom)
				(hide yes)
			)
		)
		(property "Manufacturer" "Bourns"
			(at 184.15 160.02 0)
			(effects
				(font
					(size 1.27 1.27)
					(thickness 0.15)
				)
				(justify left bottom)
				(hide yes)
			)
		)
		(property "License" "Apache-2.0"
			(at 184.15 162.56 0)
			(effects
				(font
					(size 1.27 1.27)
					(thickness 0.15)
				)
				(justify left bottom)
				(hide yes)
			)
		)
		(property "Author" "Antmicro"
			(at 184.15 165.1 0)
			(effects
				(font
					(size 1.27 1.27)
					(thickness 0.15)
				)
				(justify left bottom)
				(hide yes)
			)
		)
		(property "Val" "10k"
			(at 166.37 139.7 0)
			(effects
				(font
					(size 1.27 1.27)
					(thickness 0.15)
				)
			)
		)
		(property "Tolerance" "1%"
			(at 184.15 147.32 0)
			(effects
				(font
					(size 1.27 1.27)
				)
				(justify left bottom)
				(hide yes)
			)
		)
		(pin "2"
		)
		(pin "1"
		)
		(instances
			(project ""
				(path ""
					(reference "R175")
					(unit 1)
				)
			)
		)
	)
	(symbol
		(lib_id "antmicroResistors0402:R_10k_0402")
		(at 180.34 171.45 270)
		(mirror x)
		(unit 1)
		(exclude_from_sim no)
		(in_bom yes)
		(on_board yes)
		(dnp no)
		(property "Reference" "R179"
			(at 179.07 167.64 90)
			(effects
				(font
					(size 1.27 1.27)
					(thickness 0.15)
				)
				(justify right)
			)
		)
		(property "Value" "R_10k_0402"
			(at 167.64 151.13 0)
			(effects
				(font
					(size 1.27 1.27)
					(thickness 0.15)
				)
				(justify left bottom)
				(hide yes)
			)
		)
		(property "Footprint" "antmicro-footprints:R_0402_1005Metric"
			(at 165.1 151.13 0)
			(effects
				(font
					(size 1.27 1.27)
					(thickness 0.15)
				)
				(justify left bottom)
				(hide yes)
			)
		)
		(property "Datasheet" "https://www.bourns.com/docs/product-datasheets/cr.pdf"
			(at 162.56 151.13 0)
			(effects
				(font
					(size 1.27 1.27)
					(thickness 0.15)
				)
				(justify left bottom)
				(hide yes)
			)
		)
		(property "Description" "SMD Chip Resistor, 10 kohm, ± 1%, 62.5 mW, 0402 [1005 Metric], Thick Film, General Purpose"
			(at 149.86 151.13 0)
			(effects
				(font
					(size 1.27 1.27)
				)
				(justify left bottom)
				(hide yes)
			)
		)
		(property "MPN" "CR0402-FX-1002GLF"
			(at 160.02 151.13 0)
			(effects
				(font
					(size 1.27 1.27)
					(thickness 0.15)
				)
				(justify left bottom)
				(hide yes)
			)
		)
		(property "Manufacturer" "Bourns"
			(at 157.48 151.13 0)
			(effects
				(font
					(size 1.27 1.27)
					(thickness 0.15)
				)
				(justify left bottom)
				(hide yes)
			)
		)
		(property "License" "Apache-2.0"
			(at 154.94 151.13 0)
			(effects
				(font
					(size 1.27 1.27)
					(thickness 0.15)
				)
				(justify left bottom)
				(hide yes)
			)
		)
		(property "Author" "Antmicro"
			(at 152.4 151.13 0)
			(effects
				(font
					(size 1.27 1.27)
					(thickness 0.15)
				)
				(justify left bottom)
				(hide yes)
			)
		)
		(property "Val" "10k"
			(at 179.07 170.18 90)
			(effects
				(font
					(size 1.27 1.27)
					(thickness 0.15)
				)
				(justify right)
			)
		)
		(property "Tolerance" "1%"
			(at 170.18 151.13 0)
			(effects
				(font
					(size 1.27 1.27)
				)
				(justify left bottom)
				(hide yes)
			)
		)
		(pin "2"
		)
		(pin "1"
		)
		(instances
			(project "oculink-to-10gbe-adapter"
				(path ""
					(reference "R179")
					(unit 1)
				)
			)
		)
	)
	(symbol
		(lib_id "antmicroResistors0402:R_1k_0402")
		(at 180.34 181.61 270)
		(mirror x)
		(unit 1)
		(exclude_from_sim no)
		(in_bom yes)
		(on_board yes)
		(dnp no)
		(property "Reference" "R178"
			(at 179.07 177.8 90)
			(effects
				(font
					(size 1.27 1.27)
					(thickness 0.15)
				)
				(justify right)
			)
		)
		(property "Value" "R_1k_0402"
			(at 167.64 161.29 0)
			(effects
				(font
					(size 1.27 1.27)
					(thickness 0.15)
				)
				(justify left bottom)
				(hide yes)
			)
		)
		(property "Footprint" "antmicro-footprints:R_0402_1005Metric"
			(at 165.1 161.29 0)
			(effects
				(font
					(size 1.27 1.27)
					(thickness 0.15)
				)
				(justify left bottom)
				(hide yes)
			)
		)
		(property "Datasheet" "https://www.bourns.com/docs/product-datasheets/cr.pdf"
			(at 162.56 161.29 0)
			(effects
				(font
					(size 1.27 1.27)
					(thickness 0.15)
				)
				(justify left bottom)
				(hide yes)
			)
		)
		(property "Description" "SMD Chip Resistor, 1 kohm, ± 1%, 63 mW, 0402 [1005 Metric], Thick Film, General Purpose"
			(at 149.86 161.29 0)
			(effects
				(font
					(size 1.27 1.27)
				)
				(justify left bottom)
				(hide yes)
			)
		)
		(property "MPN" "CR0402-FX-1001GLF"
			(at 160.02 161.29 0)
			(effects
				(font
					(size 1.27 1.27)
					(thickness 0.15)
				)
				(justify left bottom)
				(hide yes)
			)
		)
		(property "Manufacturer" "Bourns"
			(at 157.48 161.29 0)
			(effects
				(font
					(size 1.27 1.27)
					(thickness 0.15)
				)
				(justify left bottom)
				(hide yes)
			)
		)
		(property "License" "Apache-2.0"
			(at 154.94 161.29 0)
			(effects
				(font
					(size 1.27 1.27)
					(thickness 0.15)
				)
				(justify left bottom)
				(hide yes)
			)
		)
		(property "Author" "Antmicro"
			(at 152.4 161.29 0)
			(effects
				(font
					(size 1.27 1.27)
					(thickness 0.15)
				)
				(justify left bottom)
				(hide yes)
			)
		)
		(property "Val" "1k"
			(at 179.07 180.34 90)
			(effects
				(font
					(size 1.27 1.27)
					(thickness 0.15)
				)
				(justify right)
			)
		)
		(property "Tolerance" "1%"
			(at 170.18 161.29 0)
			(effects
				(font
					(size 1.27 1.27)
				)
				(justify left bottom)
				(hide yes)
			)
		)
		(pin "2"
		)
		(pin "1"
		)
		(instances
			(project ""
				(path ""
					(reference "R178")
					(unit 1)
				)
			)
		)
	)
	(symbol
		(lib_id "antmicroCapacitors0603:C_10u_10V_X7R_0603")
		(at 95.25 149.86 90)
		(unit 1)
		(exclude_from_sim no)
		(in_bom yes)
		(on_board yes)
		(dnp no)
		(fields_autoplaced yes)
		(property "Reference" "C214"
			(at 97.79 146.0436 90)
			(effects
				(font
					(size 1.27 1.27)
					(thickness 0.15)
				)
				(justify right)
			)
		)
		(property "Value" "C_10u_10V_X7R_0603"
			(at 105.41 134.62 0)
			(effects
				(font
					(size 1.27 1.27)
					(thickness 0.15)
				)
				(justify left bottom)
				(hide yes)
			)
		)
		(property "Footprint" "antmicro-footprints:C_0603_1608Metric"
			(at 107.95 134.62 0)
			(effects
				(font
					(size 1.27 1.27)
					(thickness 0.15)
				)
				(justify left bottom)
				(hide yes)
			)
		)
		(property "Datasheet" "https://www.murata.com/products/productdetail?partno=GRM188Z71A106KA73%23"
			(at 110.49 134.62 0)
			(effects
				(font
					(size 1.27 1.27)
					(thickness 0.15)
				)
				(justify left bottom)
				(hide yes)
			)
		)
		(property "Description" "SMD Multilayer Ceramic Capacitor,  10µF, 10V, 0603, ±10%, X7R"
			(at 128.27 134.62 0)
			(effects
				(font
					(size 1.27 1.27)
				)
				(justify left bottom)
				(hide yes)
			)
		)
		(property "MPN" "GRM188Z71A106KA73D"
			(at 113.03 134.62 0)
			(effects
				(font
					(size 1.27 1.27)
					(thickness 0.15)
				)
				(justify left bottom)
				(hide yes)
			)
		)
		(property "Val" "10u"
			(at 97.79 148.5836 90)
			(effects
				(font
					(size 1.27 1.27)
					(thickness 0.15)
				)
				(justify right)
			)
		)
		(property "Voltage" "10V"
			(at 115.57 134.62 0)
			(effects
				(font
					(size 1.27 1.27)
					(thickness 0.15)
				)
				(justify left bottom)
				(hide yes)
			)
		)
		(property "Dielectric" "X7R"
			(at 118.11 134.62 0)
			(effects
				(font
					(size 1.27 1.27)
					(thickness 0.15)
				)
				(justify left bottom)
				(hide yes)
			)
		)
		(property "Manufacturer" "Murata"
			(at 120.65 134.62 0)
			(effects
				(font
					(size 1.27 1.27)
					(thickness 0.15)
				)
				(justify left bottom)
				(hide yes)
			)
		)
		(property "License" "Apache-2.0"
			(at 123.19 134.62 0)
			(effects
				(font
					(size 1.27 1.27)
					(thickness 0.15)
				)
				(justify left bottom)
				(hide yes)
			)
		)
		(property "Author" "Antmicro"
			(at 125.73 134.62 0)
			(effects
				(font
					(size 1.27 1.27)
					(thickness 0.15)
				)
				(justify left bottom)
				(hide yes)
			)
		)
		(pin "1"
		)
		(pin "2"
		)
		(instances
			(project ""
				(path ""
					(reference "C214")
					(unit 1)
				)
			)
		)
	)
	(symbol
		(lib_id "antmicroResistors0402:R_0R_0402")
		(at 193.04 171.45 90)
		(unit 1)
		(exclude_from_sim no)
		(in_bom no)
		(on_board yes)
		(dnp yes)
		(property "Reference" "R177"
			(at 194.31 167.64 90)
			(effects
				(font
					(size 1.27 1.27)
					(thickness 0.15)
				)
				(justify right)
			)
		)
		(property "Value" "R_0R_0402"
			(at 205.74 151.13 0)
			(effects
				(font
					(size 1.27 1.27)
					(thickness 0.15)
				)
				(justify left bottom)
				(hide yes)
			)
		)
		(property "Footprint" "antmicro-footprints:R_0402_1005Metric"
			(at 208.28 151.13 0)
			(effects
				(font
					(size 1.27 1.27)
					(thickness 0.15)
				)
				(justify left bottom)
				(hide yes)
			)
		)
		(property "Datasheet" "https://industrial.panasonic.com/cdbs/www-data/pdf/RDA0000/AOA0000C301.pdf"
			(at 210.82 151.13 0)
			(effects
				(font
					(size 1.27 1.27)
					(thickness 0.15)
				)
				(justify left bottom)
				(hide yes)
			)
		)
		(property "Description" "SMD Chip Resistor, Jumper, 0 ohm, 100 mW, 0402 [1005 Metric], Thick Film, General Purpose"
			(at 226.06 151.13 0)
			(effects
				(font
					(size 1.27 1.27)
				)
				(justify left bottom)
				(hide yes)
			)
		)
		(property "MPN" "ERJ2GE0R00X"
			(at 213.36 151.13 0)
			(effects
				(font
					(size 1.27 1.27)
					(thickness 0.15)
				)
				(justify left bottom)
				(hide yes)
			)
		)
		(property "Manufacturer" "Panasonic"
			(at 215.9 151.13 0)
			(effects
				(font
					(size 1.27 1.27)
					(thickness 0.15)
				)
				(justify left bottom)
				(hide yes)
			)
		)
		(property "License" "Apache-2.0"
			(at 218.44 151.13 0)
			(effects
				(font
					(size 1.27 1.27)
					(thickness 0.15)
				)
				(justify left bottom)
				(hide yes)
			)
		)
		(property "Author" "Antmicro"
			(at 220.98 151.13 0)
			(effects
				(font
					(size 1.27 1.27)
					(thickness 0.15)
				)
				(justify left bottom)
				(hide yes)
			)
		)
		(property "Val" "0R"
			(at 194.31 170.18 90)
			(effects
				(font
					(size 1.27 1.27)
					(thickness 0.15)
				)
				(justify right)
			)
		)
		(property "Tolerance" "~"
			(at 203.2 151.13 0)
			(effects
				(font
					(size 1.27 1.27)
				)
				(justify left bottom)
				(hide yes)
			)
		)
		(property "Current" "1A"
			(at 223.52 151.13 0)
			(effects
				(font
					(size 1.27 1.27)
					(thickness 0.15)
				)
				(justify left bottom)
				(hide yes)
			)
		)
		(pin "2"
		)
		(pin "1"
		)
		(instances
			(project "oculink-to-10gbe-adapter"
				(path ""
					(reference "R177")
					(unit 1)
				)
			)
		)
	)
	(symbol
		(lib_id "antmicropower:GND")
		(at 83.82 151.13 0)
		(unit 1)
		(exclude_from_sim no)
		(in_bom yes)
		(on_board yes)
		(dnp no)
		(property "Reference" "#PWR0359"
			(at 92.71 153.67 0)
			(effects
				(font
					(size 1.27 1.27)
					(thickness 0.15)
				)
				(justify left bottom)
				(hide yes)
			)
		)
		(property "Value" "GND"
			(at 83.82 154.94 0)
			(effects
				(font
					(size 1.27 1.27)
					(thickness 0.15)
				)
			)
		)
		(property "Footprint" ""
			(at 92.71 158.75 0)
			(effects
				(font
					(size 1.27 1.27)
					(thickness 0.15)
				)
				(justify left bottom)
				(hide yes)
			)
		)
		(property "Datasheet" ""
			(at 92.71 163.83 0)
			(effects
				(font
					(size 1.27 1.27)
					(thickness 0.15)
				)
				(justify left bottom)
				(hide yes)
			)
		)
		(property "Description" ""
			(at 83.82 151.13 0)
			(effects
				(font
					(size 1.27 1.27)
				)
				(hide yes)
			)
		)
		(property "Author" "Antmicro"
			(at 92.71 158.75 0)
			(effects
				(font
					(size 1.27 1.27)
					(thickness 0.15)
				)
				(justify left bottom)
				(hide yes)
			)
		)
		(property "License" "Apache-2.0"
			(at 92.71 161.29 0)
			(effects
				(font
					(size 1.27 1.27)
					(thickness 0.15)
				)
				(justify left bottom)
				(hide yes)
			)
		)
		(pin "1"
		)
		(instances
			(project "oculink-to-10gbe-adapter"
				(path ""
					(reference "#PWR0359")
					(unit 1)
				)
			)
		)
	)
)
